FILE_TYPE = MACRO_DRAWING;
SET COLOR_WIRE YELLOW;
SET COLOR_PROP ORANGE;
SET COLOR_DOT WHITE;
SET COLOR_ARC YELLOW;
SET COLOR_BODY GREEN;
SET COLOR_NOTE PURPLE;
SET PROP_DISPLAY VALUE;
SET PAGE_NUMBER P193;
FORCEADD UNIVERSAL_GND..1
(-9250 1400);
FORCEPROP 3 LASTPIN (-9250 1450) SIG_NAME GND\g
J 0
(-9240 1460);
DISPLAY 0.659574 (-9240 1460);
PAINT MONO (-9240 1460);
DISPLAY INVISIBLE (-9240 1460);
FORCEPROP 2 LAST CDS_LIB pure_quanta_power
J 0
(-9250 1400);
DISPLAY INVISIBLE (-9250 1400);
FORCEPROP 1 LAST HDL_POWER GND
J 1
(-9225 1325);
DISPLAY 0.872340 (-9225 1325);
PAINT GREEN (-9225 1325);
DISPLAY INVISIBLE (-9225 1325);
FORCEPROP 1 LAST PATH I1
J 0
(-9175 1400);
DISPLAY 0.872340 (-9175 1400);
PAINT AQUA (-9175 1400);
DISPLAY INVISIBLE (-9175 1400);
FORCEADD UNIVERSAL_GND..1
(-9225 4025);
FORCEPROP 3 LASTPIN (-9225 4075) SIG_NAME GND\g
J 0
(-9215 4085);
DISPLAY 0.659574 (-9215 4085);
PAINT MONO (-9215 4085);
DISPLAY INVISIBLE (-9215 4085);
FORCEPROP 2 LAST CDS_LIB pure_quanta_power
J 0
(-9225 4025);
DISPLAY INVISIBLE (-9225 4025);
FORCEPROP 1 LAST HDL_POWER GND
J 1
(-9200 3950);
DISPLAY 0.872340 (-9200 3950);
PAINT GREEN (-9200 3950);
DISPLAY INVISIBLE (-9200 3950);
FORCEPROP 1 LAST PATH I10
J 0
(-9150 4025);
DISPLAY 0.872340 (-9150 4025);
PAINT AQUA (-9150 4025);
DISPLAY INVISIBLE (-9150 4025);
FORCEADD Q_CAP..1
(-9225 4225);
FORCEPROP 1 LAST LOCATION PC374_1
J 0
(-9175 4325);
DISPLAY 0.489362 (-9175 4325);
PAINT SKYBLUE (-9175 4325);
FORCEPROP 0 LAST $SEC 1
J 0
(-9175 4350);
DISPLAY 0.680851 (-9175 4350);
PAINT MONO (-9175 4350);
DISPLAY INVISIBLE (-9175 4350);
FORCEPROP 0 LAST CDS_SEC 1
J 0
(-8975 4275);
DISPLAY 1.021277 (-8975 4275);
DISPLAY INVISIBLE (-8975 4275);
FORCEPROP 1 LASTPIN (-9225 4325) $PN 1
J 0
(-9215 4305);
DISPLAY 0.489362 (-9215 4305);
PAINT MONO (-9215 4305);
FORCEPROP 1 LASTPIN (-9225 4125) $PN 2
J 0
(-9215 4105);
DISPLAY 0.489362 (-9215 4105);
PAINT MONO (-9215 4105);
FORCEPROP 1 LAST MATERIAL X7R
J 0
(-9175 4125);
DISPLAY 0.489362 (-9175 4125);
PAINT SKYBLUE (-9175 4125);
FORCEPROP 1 LAST TOLERANCE 10%
J 0
(-9175 4175);
DISPLAY 0.489362 (-9175 4175);
PAINT SKYBLUE (-9175 4175);
FORCEPROP 1 LAST PACK_TYPE 0402
J 0
(-9175 4025);
DISPLAY 0.489362 (-9175 4025);
PAINT SKYBLUE (-9175 4025);
FORCEPROP 1 LAST VALUE 0.1UF
J 0
(-9175 4275);
DISPLAY 0.489362 (-9175 4275);
PAINT SKYBLUE (-9175 4275);
FORCEPROP 1 LAST VOLTAGE 25V
J 0
(-9175 4225);
DISPLAY 0.489362 (-9175 4225);
PAINT SKYBLUE (-9175 4225);
FORCEPROP 2 LAST CDS_LIB pure_quanta
J 0
(-9225 4225);
DISPLAY INVISIBLE (-9225 4225);
FORCEPROP 1 LAST PATH I11
J 0
(-9175 4375);
DISPLAY 0.978723 (-9175 4375);
PAINT WHITE (-9175 4375);
DISPLAY INVISIBLE (-9175 4375);
FORCEPROP 1 LAST PART_NUMBER CH4104K1B00
J 0
(-9175 4075);
DISPLAY 0.489362 (-9175 4075);
PAINT SKYBLUE (-9175 4075);
DISPLAY INVISIBLE (-9175 4075);
FORCEADD Q_CAP..1
(-8475 2400);
FORCEPROP 1 LAST LOCATION PC370
J 0
(-8425 2500);
DISPLAY 0.489362 (-8425 2500);
PAINT SKYBLUE (-8425 2500);
FORCEPROP 0 LAST $SEC 1
J 0
(-8425 2550);
DISPLAY 0.680851 (-8425 2550);
PAINT MONO (-8425 2550);
DISPLAY INVISIBLE (-8425 2550);
FORCEPROP 0 LAST CDS_SEC 1
J 0
(-8425 2550);
DISPLAY 1.021277 (-8425 2550);
DISPLAY INVISIBLE (-8425 2550);
FORCEPROP 1 LASTPIN (-8475 2500) $PN 1
J 0
(-8465 2480);
DISPLAY 0.489362 (-8465 2480);
PAINT MONO (-8465 2480);
FORCEPROP 1 LASTPIN (-8475 2300) $PN 2
J 0
(-8465 2280);
DISPLAY 0.489362 (-8465 2280);
PAINT MONO (-8465 2280);
FORCEPROP 1 LAST MATERIAL X6S
J 0
(-8425 2300);
DISPLAY 0.489362 (-8425 2300);
PAINT SKYBLUE (-8425 2300);
FORCEPROP 1 LAST TOLERANCE 10%
J 0
(-8425 2350);
DISPLAY 0.489362 (-8425 2350);
PAINT SKYBLUE (-8425 2350);
FORCEPROP 1 LAST VALUE 2.2UF
J 0
(-8425 2450);
DISPLAY 0.489362 (-8425 2450);
PAINT SKYBLUE (-8425 2450);
FORCEPROP 1 LAST VOLTAGE 10V
J 0
(-8425 2400);
DISPLAY 0.489362 (-8425 2400);
PAINT SKYBLUE (-8425 2400);
FORCEPROP 1 LAST PACK_TYPE C0402
J 0
(-8425 2200);
DISPLAY 0.489362 (-8425 2200);
PAINT SKYBLUE (-8425 2200);
FORCEPROP 2 LAST CDS_LIB pure_quanta
J 0
(-8475 2400);
DISPLAY INVISIBLE (-8475 2400);
FORCEPROP 1 LAST PATH I12
J 0
(-8425 2550);
DISPLAY 0.978723 (-8425 2550);
PAINT WHITE (-8425 2550);
DISPLAY INVISIBLE (-8425 2550);
FORCEPROP 1 LAST PART_NUMBER CH5222KEB01
J 0
(-8425 2250);
DISPLAY 0.489362 (-8425 2250);
PAINT SKYBLUE (-8425 2250);
DISPLAY INVISIBLE (-8425 2250);
FORCEADD UNIVERSAL_GND..1
(-8125 2700);
FORCEPROP 3 LASTPIN (-8125 2750) SIG_NAME GND\g
J 0
(-8115 2760);
DISPLAY 0.659574 (-8115 2760);
PAINT MONO (-8115 2760);
DISPLAY INVISIBLE (-8115 2760);
FORCEPROP 2 LAST CDS_LIB pure_quanta_power
J 0
(-8125 2700);
DISPLAY INVISIBLE (-8125 2700);
FORCEPROP 1 LAST HDL_POWER GND
J 1
(-8100 2625);
DISPLAY 0.872340 (-8100 2625);
PAINT GREEN (-8100 2625);
DISPLAY INVISIBLE (-8100 2625);
FORCEPROP 1 LAST PATH I13
J 0
(-8050 2700);
DISPLAY 0.872340 (-8050 2700);
PAINT AQUA (-8050 2700);
DISPLAY INVISIBLE (-8050 2700);
FORCEADD Q_RES..2
(-8475 2950);
FORCEPROP 1 LAST LOCATION PR257
J 0
(-8430 3075);
DISPLAY 0.489362 (-8430 3075);
PAINT SKYBLUE (-8430 3075);
FORCEPROP 0 LAST $SEC 1
J 0
(-8425 3125);
DISPLAY 0.680851 (-8425 3125);
PAINT MONO (-8425 3125);
DISPLAY INVISIBLE (-8425 3125);
FORCEPROP 0 LAST CDS_SEC 1
J 0
(-8425 3125);
DISPLAY 1.021277 (-8425 3125);
DISPLAY INVISIBLE (-8425 3125);
FORCEPROP 1 LASTPIN (-8475 3050) $PN 1
J 0
(-8470 3012);
DISPLAY 0.489362 (-8470 3012);
PAINT MONO (-8470 3012);
FORCEPROP 1 LASTPIN (-8475 2850) $PN 2
J 0
(-8470 2860);
DISPLAY 0.489362 (-8470 2860);
PAINT MONO (-8470 2860);
FORCEPROP 1 LAST VALUE 2.2
J 0
(-8425 3025);
DISPLAY 0.489362 (-8425 3025);
PAINT SKYBLUE (-8425 3025);
FORCEPROP 1 LAST TOLERANCE 1%
J 0
(-8425 2975);
DISPLAY 0.489362 (-8425 2975);
PAINT SKYBLUE (-8425 2975);
FORCEPROP 1 LAST MATERIAL CHIP
J 0
(-8425 2875);
DISPLAY 0.489362 (-8425 2875);
PAINT SKYBLUE (-8425 2875);
FORCEPROP 1 LAST WATTAGE 1/16W
J 0
(-8425 2925);
DISPLAY 0.489362 (-8425 2925);
PAINT SKYBLUE (-8425 2925);
FORCEPROP 1 LAST PACK_TYPE 0402LF
J 0
(-8425 2775);
DISPLAY 0.489362 (-8425 2775);
PAINT SKYBLUE (-8425 2775);
FORCEPROP 2 LAST CDS_LIB pure_quanta
J 0
(-8475 2950);
DISPLAY INVISIBLE (-8475 2950);
FORCEPROP 1 LAST PATH I14
J 0
(-8425 3125);
DISPLAY 0.978723 (-8425 3125);
PAINT WHITE (-8425 3125);
DISPLAY INVISIBLE (-8425 3125);
FORCEPROP 1 LAST PART_NUMBER CS-2202FB01
J 0
(-8425 2825);
DISPLAY 0.489362 (-8425 2825);
PAINT SKYBLUE (-8425 2825);
DISPLAY INVISIBLE (-8425 2825);
FORCEADD Q_CAP..1
(-8125 2975);
FORCEPROP 1 LAST LOCATION PC372_C1P1_2
J 0
(-8075 3075);
DISPLAY 0.489362 (-8075 3075);
PAINT SKYBLUE (-8075 3075);
FORCEPROP 0 LAST $SEC 1
J 0
(-8075 3125);
DISPLAY 0.680851 (-8075 3125);
PAINT MONO (-8075 3125);
DISPLAY INVISIBLE (-8075 3125);
FORCEPROP 0 LAST CDS_SEC 1
J 0
(-8075 3125);
DISPLAY 1.021277 (-8075 3125);
DISPLAY INVISIBLE (-8075 3125);
FORCEPROP 1 LASTPIN (-8125 3075) $PN 1
J 0
(-8115 3055);
DISPLAY 0.489362 (-8115 3055);
PAINT MONO (-8115 3055);
FORCEPROP 1 LASTPIN (-8125 2875) $PN 2
J 0
(-8115 2855);
DISPLAY 0.489362 (-8115 2855);
PAINT MONO (-8115 2855);
FORCEPROP 1 LAST MATERIAL X6S
J 0
(-8075 2875);
DISPLAY 0.489362 (-8075 2875);
PAINT SKYBLUE (-8075 2875);
FORCEPROP 1 LAST TOLERANCE 10%
J 0
(-8075 2925);
DISPLAY 0.489362 (-8075 2925);
PAINT SKYBLUE (-8075 2925);
FORCEPROP 1 LAST VALUE 2.2UF
J 0
(-8075 3025);
DISPLAY 0.489362 (-8075 3025);
PAINT SKYBLUE (-8075 3025);
FORCEPROP 1 LAST VOLTAGE 10V
J 0
(-8075 2975);
DISPLAY 0.489362 (-8075 2975);
PAINT SKYBLUE (-8075 2975);
FORCEPROP 1 LAST PACK_TYPE C0402
J 0
(-8075 2775);
DISPLAY 0.489362 (-8075 2775);
PAINT SKYBLUE (-8075 2775);
FORCEPROP 2 LAST CDS_LIB pure_quanta
J 0
(-8125 2975);
DISPLAY INVISIBLE (-8125 2975);
FORCEPROP 1 LAST PATH I15
J 0
(-8075 3125);
DISPLAY 0.978723 (-8075 3125);
PAINT WHITE (-8075 3125);
DISPLAY INVISIBLE (-8075 3125);
FORCEPROP 1 LAST PART_NUMBER CH5222KEB01
J 0
(-8075 2825);
DISPLAY 0.489362 (-8075 2825);
PAINT SKYBLUE (-8075 2825);
DISPLAY INVISIBLE (-8075 2825);
FORCEADD UNIVERSAL_GND..1
(-8725 3875);
FORCEPROP 3 LASTPIN (-8725 3925) SIG_NAME GND\g
J 0
(-8715 3935);
DISPLAY 0.659574 (-8715 3935);
PAINT MONO (-8715 3935);
DISPLAY INVISIBLE (-8715 3935);
FORCEPROP 2 LAST CDS_LIB pure_quanta_power
J 0
(-8725 3875);
PAINT MONO (-8725 3875);
DISPLAY INVISIBLE (-8725 3875);
FORCEPROP 1 LAST HDL_POWER GND
J 1
(-8700 3800);
DISPLAY 0.872340 (-8700 3800);
PAINT GREEN (-8700 3800);
DISPLAY INVISIBLE (-8700 3800);
FORCEPROP 1 LAST PATH I16
J 0
(-8650 3875);
DISPLAY 0.872340 (-8650 3875);
PAINT AQUA (-8650 3875);
DISPLAY INVISIBLE (-8650 3875);
FORCEADD Q_RES..2
R 2
(-8725 4100);
FORCEPROP 1 LAST LOCATION PR255
J 2
(-8770 4225);
DISPLAY 0.489362 (-8770 4225);
PAINT SKYBLUE (-8770 4225);
FORCEPROP 0 LAST $SEC 1
J 0
(-8750 4275);
DISPLAY 0.680851 (-8750 4275);
PAINT MONO (-8750 4275);
DISPLAY INVISIBLE (-8750 4275);
FORCEPROP 0 LAST CDS_SEC 1
J 0
(-8750 4275);
DISPLAY 1.021277 (-8750 4275);
DISPLAY INVISIBLE (-8750 4275);
FORCEPROP 1 LASTPIN (-8725 4200) $PN 1
J 2
(-8730 4162);
DISPLAY 0.489362 (-8730 4162);
PAINT MONO (-8730 4162);
FORCEPROP 1 LASTPIN (-8725 4000) $PN 2
J 2
(-8730 4010);
DISPLAY 0.489362 (-8730 4010);
PAINT MONO (-8730 4010);
FORCEPROP 1 LAST WATTAGE 1/16W
J 2
(-8765 4075);
DISPLAY 0.489362 (-8765 4075);
PAINT SKYBLUE (-8765 4075);
FORCEPROP 1 LAST MATERIAL EMPTY
J 2
(-8765 4025);
DISPLAY 0.489362 (-8765 4025);
PAINT RED (-8765 4025);
FORCEPROP 1 LAST TOLERANCE 1%
J 2
(-8770 4125);
DISPLAY 0.489362 (-8770 4125);
PAINT SKYBLUE (-8770 4125);
FORCEPROP 1 LAST PACK_TYPE 0402LF
J 2
(-8765 3925);
DISPLAY 0.489362 (-8765 3925);
PAINT SKYBLUE (-8765 3925);
FORCEPROP 1 LAST VALUE 8.87K
J 2
(-8770 4175);
DISPLAY 0.489362 (-8770 4175);
PAINT SKYBLUE (-8770 4175);
FORCEPROP 2 LAST CDS_LIB pure_quanta
J 2
(-8725 4100);
DISPLAY INVISIBLE (-8725 4100);
FORCEPROP 1 LAST PATH I17
J 2
(-8775 4275);
DISPLAY 0.978723 (-8775 4275);
PAINT WHITE (-8775 4275);
DISPLAY INVISIBLE (-8775 4275);
FORCEPROP 1 LAST PART_NUMBER CS28872FB01
J 2
(-8765 3975);
DISPLAY 0.489362 (-8765 3975);
PAINT SKYBLUE (-8765 3975);
DISPLAY INVISIBLE (-8765 3975);
FORCEADD VCC_CORE..1
(-8475 3350);
FORCEPROP 3 LASTPIN (-8475 3300) SIG_NAME PVDDCR_CPU1_P1_PVCC\g
J 0
(-8465 3310);
DISPLAY 0.659574 (-8465 3310);
PAINT MONO (-8465 3310);
DISPLAY INVISIBLE (-8465 3310);
FORCEPROP 1 LAST HDL_POWER PVDDCR_CPU1_P1_PVCC
J 1
(-8475 3400);
DISPLAY 0.489362 (-8475 3400);
PAINT GREEN (-8475 3400);
FORCEPROP 2 LAST CDS_LIB pure_quanta_power
J 0
(-8475 3350);
DISPLAY INVISIBLE (-8475 3350);
FORCEPROP 1 LAST PATH I18
J 0
(-8425 3375);
DISPLAY 0.872340 (-8425 3375);
PAINT AQUA (-8425 3375);
DISPLAY INVISIBLE (-8425 3375);
FORCEADD OFFPAGE..1
(-8150 4000);
FORCEPROP 2 LAST $XR0 217 
J 0
(-8432 4000);
DISPLAY 0.638298 (-8432 4000);
PAINT MONO (-8432 4000);
FORCEPROP 2 LAST CDS_LIB standard
J 0
(-8150 4000);
DISPLAY INVISIBLE (-8150 4000);
FORCEPROP 1 LAST OFFPAGE TRUE
J 0
(-7825 3875);
DISPLAY 0.872340 (-7825 3875);
PAINT GREEN (-7825 3875);
DISPLAY INVISIBLE (-7825 3875);
FORCEPROP 1 LAST COMMENT_BODY TRUE
J 0
(-8025 3900);
DISPLAY 0.872340 (-8025 3900);
PAINT GREEN (-8025 3900);
DISPLAY INVISIBLE (-8025 3900);
FORCEPROP 2 LAST PATH I19
J 0
(-8400 4050);
DISPLAY 0.680851 (-8400 4050);
DISPLAY INVISIBLE (-8400 4050);
FORCEADD Q_CAP..1
(-9250 1600);
FORCEPROP 1 LAST LOCATION PC373_2
J 0
(-9200 1700);
DISPLAY 0.489362 (-9200 1700);
PAINT SKYBLUE (-9200 1700);
FORCEPROP 0 LAST $SEC 1
J 0
(-9200 1725);
DISPLAY 0.680851 (-9200 1725);
PAINT MONO (-9200 1725);
DISPLAY INVISIBLE (-9200 1725);
FORCEPROP 0 LAST CDS_SEC 1
J 0
(-9000 1650);
DISPLAY 1.021277 (-9000 1650);
DISPLAY INVISIBLE (-9000 1650);
FORCEPROP 1 LASTPIN (-9250 1700) $PN 1
J 0
(-9240 1680);
DISPLAY 0.489362 (-9240 1680);
PAINT MONO (-9240 1680);
FORCEPROP 1 LASTPIN (-9250 1500) $PN 2
J 0
(-9240 1480);
DISPLAY 0.489362 (-9240 1480);
PAINT MONO (-9240 1480);
FORCEPROP 1 LAST VALUE 0.1UF
J 0
(-9200 1650);
DISPLAY 0.489362 (-9200 1650);
PAINT SKYBLUE (-9200 1650);
FORCEPROP 1 LAST TOLERANCE 10%
J 0
(-9200 1550);
DISPLAY 0.489362 (-9200 1550);
PAINT SKYBLUE (-9200 1550);
FORCEPROP 1 LAST MATERIAL X7R
J 0
(-9200 1500);
DISPLAY 0.489362 (-9200 1500);
PAINT SKYBLUE (-9200 1500);
FORCEPROP 1 LAST PACK_TYPE 0402
J 0
(-9200 1400);
DISPLAY 0.489362 (-9200 1400);
PAINT SKYBLUE (-9200 1400);
FORCEPROP 1 LAST VOLTAGE 25V
J 0
(-9200 1600);
DISPLAY 0.489362 (-9200 1600);
PAINT SKYBLUE (-9200 1600);
FORCEPROP 2 LAST CDS_LIB pure_quanta
J 0
(-9250 1600);
DISPLAY INVISIBLE (-9250 1600);
FORCEPROP 1 LAST PATH I2
J 0
(-9200 1750);
DISPLAY 0.978723 (-9200 1750);
PAINT WHITE (-9200 1750);
DISPLAY INVISIBLE (-9200 1750);
FORCEPROP 1 LAST PART_NUMBER CH4104K1B00
J 0
(-9200 1450);
DISPLAY 0.489362 (-9200 1450);
PAINT SKYBLUE (-9200 1450);
DISPLAY INVISIBLE (-9200 1450);
FORCEADD OFFPAGE..5
(-8150 4100);
FORCEPROP 2 LAST $XR3 217 
J 0
(-8525 4064);
DISPLAY 0.638298 (-8525 4064);
PAINT MONO (-8525 4064);
FORCEPROP 2 LAST $XR2 220 
J 0
(-8405 4064);
DISPLAY 0.638298 (-8405 4064);
PAINT MONO (-8405 4064);
FORCEPROP 2 LAST $XR1 219 
J 0
(-8525 4100);
DISPLAY 0.638298 (-8525 4100);
PAINT MONO (-8525 4100);
FORCEPROP 2 LAST $XR0 218 
J 0
(-8405 4100);
DISPLAY 0.638298 (-8405 4100);
PAINT MONO (-8405 4100);
FORCEPROP 2 LAST CDS_LIB standard
J 0
(-8150 4100);
DISPLAY INVISIBLE (-8150 4100);
FORCEPROP 1 LAST OFFPAGE TRUE
J 0
(-7825 3975);
DISPLAY 0.872340 (-7825 3975);
PAINT GREEN (-7825 3975);
DISPLAY INVISIBLE (-7825 3975);
FORCEPROP 1 LAST COMMENT_BODY TRUE
J 0
(-8050 4025);
DISPLAY 0.872340 (-8050 4025);
PAINT GREEN (-8050 4025);
DISPLAY INVISIBLE (-8050 4025);
FORCEPROP 2 LAST PATH I20
J 0
(-8425 4150);
DISPLAY 0.680851 (-8425 4150);
DISPLAY INVISIBLE (-8425 4150);
FORCEADD VCC_CORE..1
(-9225 6200);
FORCEPROP 3 LASTPIN (-9225 6150) SIG_NAME P5V_AUX\g
J 0
(-9215 6160);
DISPLAY 0.659574 (-9215 6160);
PAINT MONO (-9215 6160);
DISPLAY INVISIBLE (-9215 6160);
FORCEPROP 1 LAST HDL_POWER P5V_AUX
J 1
(-9225 6250);
DISPLAY 0.489362 (-9225 6250);
PAINT GREEN (-9225 6250);
FORCEPROP 2 LAST CDS_LIB pure_quanta_power
J 0
(-9225 6200);
DISPLAY INVISIBLE (-9225 6200);
FORCEPROP 1 LAST PATH I21
J 0
(-9175 6225);
DISPLAY 0.872340 (-9175 6225);
PAINT AQUA (-9175 6225);
DISPLAY INVISIBLE (-9175 6225);
FORCEADD UNIVERSAL_GND..1
(-8575 4850);
FORCEPROP 3 LASTPIN (-8575 4900) SIG_NAME GND\g
J 0
(-8565 4910);
DISPLAY 0.659574 (-8565 4910);
PAINT MONO (-8565 4910);
DISPLAY INVISIBLE (-8565 4910);
FORCEPROP 2 LAST CDS_LIB pure_quanta_power
J 0
(-8575 4850);
DISPLAY INVISIBLE (-8575 4850);
FORCEPROP 1 LAST HDL_POWER GND
J 1
(-8550 4775);
DISPLAY 0.872340 (-8550 4775);
PAINT GREEN (-8550 4775);
DISPLAY INVISIBLE (-8550 4775);
FORCEPROP 1 LAST PATH I22
J 0
(-8500 4850);
DISPLAY 0.872340 (-8500 4850);
PAINT AQUA (-8500 4850);
DISPLAY INVISIBLE (-8500 4850);
FORCEADD Q_CAP..1
(-8575 5050);
FORCEPROP 1 LAST LOCATION PC369
J 0
(-8525 5150);
DISPLAY 0.489362 (-8525 5150);
PAINT SKYBLUE (-8525 5150);
FORCEPROP 0 LAST $SEC 1
J 0
(-8525 5200);
DISPLAY 0.680851 (-8525 5200);
PAINT MONO (-8525 5200);
DISPLAY INVISIBLE (-8525 5200);
FORCEPROP 0 LAST CDS_SEC 1
J 0
(-8525 5200);
DISPLAY 1.021277 (-8525 5200);
DISPLAY INVISIBLE (-8525 5200);
FORCEPROP 1 LASTPIN (-8575 5150) $PN 1
J 0
(-8565 5130);
DISPLAY 0.489362 (-8565 5130);
PAINT MONO (-8565 5130);
FORCEPROP 1 LASTPIN (-8575 4950) $PN 2
J 0
(-8565 4930);
DISPLAY 0.489362 (-8565 4930);
PAINT MONO (-8565 4930);
FORCEPROP 1 LAST MATERIAL X6S
J 0
(-8525 4950);
DISPLAY 0.489362 (-8525 4950);
PAINT SKYBLUE (-8525 4950);
FORCEPROP 1 LAST TOLERANCE 10%
J 0
(-8525 5000);
DISPLAY 0.489362 (-8525 5000);
PAINT SKYBLUE (-8525 5000);
FORCEPROP 1 LAST VALUE 2.2UF
J 0
(-8525 5100);
DISPLAY 0.489362 (-8525 5100);
PAINT SKYBLUE (-8525 5100);
FORCEPROP 1 LAST VOLTAGE 10V
J 0
(-8525 5050);
DISPLAY 0.489362 (-8525 5050);
PAINT SKYBLUE (-8525 5050);
FORCEPROP 1 LAST PACK_TYPE C0402
J 0
(-8525 4850);
DISPLAY 0.489362 (-8525 4850);
PAINT SKYBLUE (-8525 4850);
FORCEPROP 2 LAST CDS_LIB pure_quanta
J 0
(-8575 5050);
DISPLAY INVISIBLE (-8575 5050);
FORCEPROP 1 LAST PATH I23
J 0
(-8525 5200);
DISPLAY 0.978723 (-8525 5200);
PAINT WHITE (-8525 5200);
DISPLAY INVISIBLE (-8525 5200);
FORCEPROP 1 LAST PART_NUMBER CH5222KEB01
J 0
(-8525 4900);
DISPLAY 0.489362 (-8525 4900);
PAINT SKYBLUE (-8525 4900);
DISPLAY INVISIBLE (-8525 4900);
FORCEADD OFFPAGE..1
(-8150 4500);
FORCEPROP 2 LAST $XR5 223 
J 0
(-9032 4500);
DISPLAY 0.638298 (-9032 4500);
PAINT MONO (-9032 4500);
FORCEPROP 2 LAST $XR4 222 
J 0
(-8912 4500);
DISPLAY 0.638298 (-8912 4500);
PAINT MONO (-8912 4500);
FORCEPROP 2 LAST $XR3 220 
J 0
(-8792 4500);
DISPLAY 0.638298 (-8792 4500);
PAINT MONO (-8792 4500);
FORCEPROP 2 LAST $XR2 219 
J 0
(-8672 4500);
DISPLAY 0.638298 (-8672 4500);
PAINT MONO (-8672 4500);
FORCEPROP 2 LAST $XR1 218 
J 0
(-8552 4500);
DISPLAY 0.638298 (-8552 4500);
PAINT MONO (-8552 4500);
FORCEPROP 2 LAST $XR0 217 
J 0
(-8432 4500);
DISPLAY 0.638298 (-8432 4500);
PAINT MONO (-8432 4500);
FORCEPROP 2 LAST CDS_LIB standard
J 0
(-8150 4500);
DISPLAY INVISIBLE (-8150 4500);
FORCEPROP 1 LAST OFFPAGE TRUE
J 0
(-7825 4375);
DISPLAY 0.872340 (-7825 4375);
PAINT GREEN (-7825 4375);
DISPLAY INVISIBLE (-7825 4375);
FORCEPROP 1 LAST COMMENT_BODY TRUE
J 0
(-8025 4400);
DISPLAY 0.872340 (-8025 4400);
PAINT GREEN (-8025 4400);
DISPLAY INVISIBLE (-8025 4400);
FORCEPROP 2 LAST PATH I24
J 0
(-8400 4550);
DISPLAY 0.680851 (-8400 4550);
DISPLAY INVISIBLE (-8400 4550);
FORCEADD OFFPAGE..5
(-8150 4600);
FORCEPROP 2 LAST $XR0 217 
J 0
(-8405 4600);
DISPLAY 0.638298 (-8405 4600);
PAINT MONO (-8405 4600);
FORCEPROP 2 LAST CDS_LIB standard
J 0
(-8150 4600);
DISPLAY INVISIBLE (-8150 4600);
FORCEPROP 1 LAST OFFPAGE TRUE
J 0
(-7825 4475);
DISPLAY 0.872340 (-7825 4475);
PAINT GREEN (-7825 4475);
DISPLAY INVISIBLE (-7825 4475);
FORCEPROP 1 LAST COMMENT_BODY TRUE
J 0
(-8050 4525);
DISPLAY 0.872340 (-8050 4525);
PAINT GREEN (-8050 4525);
DISPLAY INVISIBLE (-8050 4525);
FORCEPROP 2 LAST PATH I25
J 0
(-8425 4650);
DISPLAY 0.680851 (-8425 4650);
DISPLAY INVISIBLE (-8425 4650);
FORCEADD VCC_CORE..1
(-8875 6200);
FORCEPROP 3 LASTPIN (-8875 6150) SIG_NAME P3V3_AUX\g
J 0
(-8865 6160);
DISPLAY 0.659574 (-8865 6160);
PAINT MONO (-8865 6160);
DISPLAY INVISIBLE (-8865 6160);
FORCEPROP 1 LAST HDL_POWER P3V3_AUX
J 1
(-8875 6250);
DISPLAY 0.489362 (-8875 6250);
PAINT GREEN (-8875 6250);
FORCEPROP 2 LAST CDS_LIB pure_quanta_power
J 0
(-8875 6200);
DISPLAY INVISIBLE (-8875 6200);
FORCEPROP 1 LAST PATH I26
J 0
(-8825 6225);
DISPLAY 0.872340 (-8825 6225);
PAINT AQUA (-8825 6225);
DISPLAY INVISIBLE (-8825 6225);
FORCEADD Q_RES..2
(-8575 5600);
FORCEPROP 1 LAST LOCATION PR256
J 0
(-8530 5725);
DISPLAY 0.489362 (-8530 5725);
PAINT SKYBLUE (-8530 5725);
FORCEPROP 0 LAST $SEC 1
J 0
(-8525 5775);
DISPLAY 0.680851 (-8525 5775);
PAINT MONO (-8525 5775);
DISPLAY INVISIBLE (-8525 5775);
FORCEPROP 0 LAST CDS_SEC 1
J 0
(-8525 5775);
DISPLAY 1.021277 (-8525 5775);
DISPLAY INVISIBLE (-8525 5775);
FORCEPROP 1 LASTPIN (-8575 5700) $PN 1
J 0
(-8570 5662);
DISPLAY 0.489362 (-8570 5662);
PAINT MONO (-8570 5662);
FORCEPROP 1 LASTPIN (-8575 5500) $PN 2
J 0
(-8570 5510);
DISPLAY 0.489362 (-8570 5510);
PAINT MONO (-8570 5510);
FORCEPROP 1 LAST MATERIAL CHIP
J 0
(-8525 5525);
DISPLAY 0.489362 (-8525 5525);
PAINT SKYBLUE (-8525 5525);
FORCEPROP 1 LAST VALUE 2.2
J 0
(-8525 5675);
DISPLAY 0.489362 (-8525 5675);
PAINT SKYBLUE (-8525 5675);
FORCEPROP 1 LAST TOLERANCE 1%
J 0
(-8525 5625);
DISPLAY 0.489362 (-8525 5625);
PAINT SKYBLUE (-8525 5625);
FORCEPROP 1 LAST WATTAGE 1/16W
J 0
(-8525 5575);
DISPLAY 0.489362 (-8525 5575);
PAINT SKYBLUE (-8525 5575);
FORCEPROP 1 LAST PACK_TYPE 0402LF
J 0
(-8525 5425);
DISPLAY 0.489362 (-8525 5425);
PAINT SKYBLUE (-8525 5425);
FORCEPROP 2 LAST CDS_LIB pure_quanta
J 0
(-8575 5600);
DISPLAY INVISIBLE (-8575 5600);
FORCEPROP 1 LAST PATH I27
J 0
(-8525 5775);
DISPLAY 0.978723 (-8525 5775);
PAINT WHITE (-8525 5775);
DISPLAY INVISIBLE (-8525 5775);
FORCEPROP 1 LAST PART_NUMBER CS-2202FB01
J 0
(-8525 5475);
DISPLAY 0.489362 (-8525 5475);
PAINT SKYBLUE (-8525 5475);
DISPLAY INVISIBLE (-8525 5475);
FORCEADD UNIVERSAL_GND..1
(-8225 5350);
FORCEPROP 3 LASTPIN (-8225 5400) SIG_NAME GND\g
J 0
(-8215 5410);
DISPLAY 0.659574 (-8215 5410);
PAINT MONO (-8215 5410);
DISPLAY INVISIBLE (-8215 5410);
FORCEPROP 2 LAST CDS_LIB pure_quanta_power
J 0
(-8225 5350);
DISPLAY INVISIBLE (-8225 5350);
FORCEPROP 1 LAST HDL_POWER GND
J 1
(-8200 5275);
DISPLAY 0.872340 (-8200 5275);
PAINT GREEN (-8200 5275);
DISPLAY INVISIBLE (-8200 5275);
FORCEPROP 1 LAST PATH I28
J 0
(-8150 5350);
DISPLAY 0.872340 (-8150 5350);
PAINT AQUA (-8150 5350);
DISPLAY INVISIBLE (-8150 5350);
FORCEADD Q_CAP..1
(-8225 5625);
FORCEPROP 1 LAST LOCATION PC371_C1P1_1
J 0
(-8175 5725);
DISPLAY 0.489362 (-8175 5725);
PAINT SKYBLUE (-8175 5725);
FORCEPROP 0 LAST $SEC 1
J 0
(-8175 5775);
DISPLAY 0.680851 (-8175 5775);
PAINT MONO (-8175 5775);
DISPLAY INVISIBLE (-8175 5775);
FORCEPROP 0 LAST CDS_SEC 1
J 0
(-8175 5775);
DISPLAY 1.021277 (-8175 5775);
DISPLAY INVISIBLE (-8175 5775);
FORCEPROP 1 LASTPIN (-8225 5725) $PN 1
J 0
(-8215 5705);
DISPLAY 0.489362 (-8215 5705);
PAINT MONO (-8215 5705);
FORCEPROP 1 LASTPIN (-8225 5525) $PN 2
J 0
(-8215 5505);
DISPLAY 0.489362 (-8215 5505);
PAINT MONO (-8215 5505);
FORCEPROP 1 LAST MATERIAL X6S
J 0
(-8175 5525);
DISPLAY 0.489362 (-8175 5525);
PAINT SKYBLUE (-8175 5525);
FORCEPROP 1 LAST TOLERANCE 10%
J 0
(-8175 5575);
DISPLAY 0.489362 (-8175 5575);
PAINT SKYBLUE (-8175 5575);
FORCEPROP 1 LAST VALUE 2.2UF
J 0
(-8175 5675);
DISPLAY 0.489362 (-8175 5675);
PAINT SKYBLUE (-8175 5675);
FORCEPROP 1 LAST VOLTAGE 10V
J 0
(-8175 5625);
DISPLAY 0.489362 (-8175 5625);
PAINT SKYBLUE (-8175 5625);
FORCEPROP 1 LAST PACK_TYPE C0402
J 0
(-8175 5425);
DISPLAY 0.489362 (-8175 5425);
PAINT SKYBLUE (-8175 5425);
FORCEPROP 2 LAST CDS_LIB pure_quanta
J 0
(-8225 5625);
DISPLAY INVISIBLE (-8225 5625);
FORCEPROP 1 LAST PATH I29
J 0
(-8175 5775);
DISPLAY 0.978723 (-8175 5775);
PAINT WHITE (-8175 5775);
DISPLAY INVISIBLE (-8175 5775);
FORCEPROP 1 LAST PART_NUMBER CH5222KEB01
J 0
(-8175 5475);
DISPLAY 0.489362 (-8175 5475);
PAINT SKYBLUE (-8175 5475);
DISPLAY INVISIBLE (-8175 5475);
FORCEADD UNIVERSAL_GND..1
(-8750 1250);
FORCEPROP 3 LASTPIN (-8750 1300) SIG_NAME GND\g
J 0
(-8740 1310);
DISPLAY 0.659574 (-8740 1310);
PAINT MONO (-8740 1310);
DISPLAY INVISIBLE (-8740 1310);
FORCEPROP 2 LAST CDS_LIB pure_quanta_power
J 0
(-8750 1250);
PAINT MONO (-8750 1250);
DISPLAY INVISIBLE (-8750 1250);
FORCEPROP 1 LAST HDL_POWER GND
J 1
(-8725 1175);
DISPLAY 0.872340 (-8725 1175);
PAINT GREEN (-8725 1175);
DISPLAY INVISIBLE (-8725 1175);
FORCEPROP 1 LAST PATH I3
J 0
(-8675 1250);
DISPLAY 0.872340 (-8675 1250);
PAINT AQUA (-8675 1250);
DISPLAY INVISIBLE (-8675 1250);
FORCEADD VCC_CORE..1
(-8375 6200);
FORCEPROP 3 LASTPIN (-8375 6150) SIG_NAME PVDDCR_CPU1_P1_PVCC\g
J 0
(-8365 6160);
DISPLAY 0.659574 (-8365 6160);
PAINT MONO (-8365 6160);
DISPLAY INVISIBLE (-8365 6160);
FORCEPROP 1 LAST HDL_POWER PVDDCR_CPU1_P1_PVCC
J 1
(-8375 6250);
DISPLAY 0.489362 (-8375 6250);
PAINT GREEN (-8375 6250);
FORCEPROP 2 LAST CDS_LIB pure_quanta_power
J 0
(-8375 6200);
DISPLAY INVISIBLE (-8375 6200);
FORCEPROP 1 LAST PATH I30
J 0
(-8325 6225);
DISPLAY 0.872340 (-8325 6225);
PAINT AQUA (-8325 6225);
DISPLAY INVISIBLE (-8325 6225);
FORCEADD ISL99390FRZTR5935..1
(-6825 1975);
FORCEPROP 1 LAST LOCATION PU5
J 0
(-7125 2850);
DISPLAY 0.489362 (-7125 2850);
PAINT SKYBLUE (-7125 2850);
FORCEPROP 2 LAST SEC 1
J 0
(-7125 3025);
DISPLAY 0.680851 (-7125 3025);
PAINT MONO (-7125 3025);
DISPLAY INVISIBLE (-7125 3025);
FORCEPROP 2 LASTPIN (-6425 1525) $PN 2
J 0
(-6415 1535);
DISPLAY 0.489362 (-6415 1535);
PAINT MONO (-6415 1535);
FORCEPROP 2 LASTPIN (-6425 2325) $PN 33
J 0
(-6415 2335);
DISPLAY 0.489362 (-6415 2335);
PAINT MONO (-6415 2335);
FORCEPROP 2 LASTPIN (-7275 1725) $PN 31
J 2
(-7285 1735);
DISPLAY 0.489362 (-7285 1735);
PAINT MONO (-7285 1735);
FORCEPROP 2 LASTPIN (-7275 2125) $PN 35
J 2
(-7285 2135);
DISPLAY 0.489362 (-7285 2135);
PAINT MONO (-7285 2135);
FORCEPROP 2 LASTPIN (-6425 1675) $PN 6
J 0
(-6415 1685);
DISPLAY 0.489362 (-6415 1685);
PAINT MONO (-6415 1685);
FORCEPROP 2 LASTPIN (-6425 1625) $PN 41
J 0
(-6415 1635);
DISPLAY 0.489362 (-6415 1635);
PAINT MONO (-6415 1635);
FORCEPROP 2 LASTPIN (-7275 1975) $PN 38
J 2
(-7285 1985);
DISPLAY 0.489362 (-7285 1985);
PAINT MONO (-7285 1985);
FORCEPROP 2 LASTPIN (-7275 1675) $PN 37
J 2
(-7285 1685);
DISPLAY 0.489362 (-7285 1685);
PAINT MONO (-7285 1685);
FORCEPROP 2 LASTPIN (-6425 1475) $PN 5
J 0
(-6415 1485);
DISPLAY 0.489362 (-6415 1485);
PAINT MONO (-6415 1485);
FORCEPROP 2 LASTPIN (-6425 1425) $PN 7_9-20_24
J 0
(-6415 1435);
DISPLAY 0.489362 (-6415 1435);
PAINT MONO (-6415 1435);
FORCEPROP 2 LASTPIN (-6425 1375) $PN 40
J 0
(-6415 1385);
DISPLAY 0.489362 (-6415 1385);
PAINT MONO (-6415 1385);
FORCEPROP 2 LASTPIN (-6425 2075) $PN 32
J 0
(-6415 2085);
DISPLAY 0.489362 (-6415 2085);
PAINT MONO (-6415 2085);
FORCEPROP 2 LASTPIN (-7275 2625) $PN 4
J 2
(-7285 2635);
DISPLAY 0.489362 (-7285 2635);
PAINT MONO (-7285 2635);
FORCEPROP 2 LASTPIN (-7275 1375) $PN 34
J 2
(-7285 1385);
DISPLAY 0.489362 (-7285 1385);
PAINT MONO (-7285 1385);
FORCEPROP 2 LASTPIN (-7275 1875) $PN 39
J 2
(-7285 1885);
DISPLAY 0.489362 (-7285 1885);
PAINT MONO (-7285 1885);
FORCEPROP 2 LASTPIN (-6425 1975) $PN 10_19
J 0
(-6415 1985);
DISPLAY 0.489362 (-6415 1985);
PAINT MONO (-6415 1985);
FORCEPROP 2 LASTPIN (-7275 1475) $PN 36
J 2
(-7285 1485);
DISPLAY 0.489362 (-7285 1485);
PAINT MONO (-7285 1485);
FORCEPROP 2 LASTPIN (-7275 2325) $PN 3
J 2
(-7285 2335);
DISPLAY 0.489362 (-7285 2335);
PAINT MONO (-7285 2335);
FORCEPROP 2 LASTPIN (-6425 2625) $PN 25_29
J 0
(-6415 2635);
DISPLAY 0.489362 (-6415 2635);
PAINT MONO (-6415 2635);
FORCEPROP 2 LASTPIN (-6425 2575) $PN 30
J 0
(-6415 2585);
DISPLAY 0.489362 (-6415 2585);
PAINT MONO (-6415 2585);
FORCEPROP 2 LASTPIN (-6425 1725) $PN 1
J 0
(-6415 1735);
DISPLAY 0.489362 (-6415 1735);
PAINT MONO (-6415 1735);
FORCEPROP 2 LAST VALUE ISL99390FRZ-TR5935
J 0
(-7125 2925);
DISPLAY 0.489362 (-7125 2925);
PAINT SKYBLUE (-7125 2925);
FORCEPROP 2 LAST PART_TYPE SMLF
J 0
(-7125 2975);
DISPLAY 0.808511 (-7125 2975);
FORCEPROP 1 LAST MATERIAL IC
J 0
(-7125 2700);
DISPLAY 0.489362 (-7125 2700);
PAINT SKYBLUE (-7125 2700);
FORCEPROP 2 LAST SEC_TYPE 
J 0
(-7125 3025);
DISPLAY 1.021277 (-7125 3025);
DISPLAY INVISIBLE (-7125 3025);
FORCEPROP 2 LAST CDS_LIB pure_quanta
J 0
(-6825 1975);
DISPLAY INVISIBLE (-6825 1975);
FORCEPROP 1 LAST CDS_LMAN_SYM_OUTLINE -300,700,250,-650
J 0
(-6825 1975);
DISPLAY 0.468085 (-6825 1975);
PAINT GREEN (-6825 1975);
DISPLAY INVISIBLE (-6825 1975);
FORCEPROP 1 LAST NEEDS_NO_SIZE TRUE
J 0
(-6825 1975);
DISPLAY 0.723404 (-6825 1975);
PAINT GREEN (-6825 1975);
DISPLAY INVISIBLE (-6825 1975);
FORCEPROP 1 LAST PATH I31
J 0
(-6825 1975);
DISPLAY 0.723404 (-6825 1975);
PAINT GREEN (-6825 1975);
DISPLAY INVISIBLE (-6825 1975);
FORCEPROP 1 LAST PART_NUMBER AL099390004
J 0
(-7125 2775);
DISPLAY 0.489362 (-7125 2775);
PAINT SKYBLUE (-7125 2775);
DISPLAY INVISIBLE (-7125 2775);
FORCEADD UNIVERSAL_GND..1
(-6175 1250);
FORCEPROP 3 LASTPIN (-6175 1300) SIG_NAME GND\g
J 0
(-6165 1310);
DISPLAY 0.659574 (-6165 1310);
PAINT MONO (-6165 1310);
DISPLAY INVISIBLE (-6165 1310);
FORCEPROP 2 LAST CDS_LIB pure_quanta_power
J 0
(-6175 1250);
PAINT MONO (-6175 1250);
DISPLAY INVISIBLE (-6175 1250);
FORCEPROP 1 LAST HDL_POWER GND
J 1
(-6150 1175);
DISPLAY 0.872340 (-6150 1175);
PAINT GREEN (-6150 1175);
DISPLAY INVISIBLE (-6150 1175);
FORCEPROP 1 LAST PATH I32
J 0
(-6100 1250);
DISPLAY 0.872340 (-6100 1250);
PAINT AQUA (-6100 1250);
DISPLAY INVISIBLE (-6100 1250);
FORCEADD UNIVERSAL_GND..1
(-6150 3875);
FORCEPROP 3 LASTPIN (-6150 3925) SIG_NAME GND\g
J 0
(-6140 3935);
DISPLAY 0.659574 (-6140 3935);
PAINT MONO (-6140 3935);
DISPLAY INVISIBLE (-6140 3935);
FORCEPROP 2 LAST CDS_LIB pure_quanta_power
J 0
(-6150 3875);
PAINT MONO (-6150 3875);
DISPLAY INVISIBLE (-6150 3875);
FORCEPROP 1 LAST HDL_POWER GND
J 1
(-6125 3800);
DISPLAY 0.872340 (-6125 3800);
PAINT GREEN (-6125 3800);
DISPLAY INVISIBLE (-6125 3800);
FORCEPROP 1 LAST PATH I33
J 0
(-6075 3875);
DISPLAY 0.872340 (-6075 3875);
PAINT AQUA (-6075 3875);
DISPLAY INVISIBLE (-6075 3875);
FORCEADD Q_CAP..1
(-6000 2875);
FORCEPROP 1 LAST LOCATION PC376_2
J 0
(-5950 3025);
DISPLAY 0.489362 (-5950 3025);
PAINT SKYBLUE (-5950 3025);
FORCEPROP 0 LAST $SEC 1
J 0
(-5950 3025);
DISPLAY 0.680851 (-5950 3025);
PAINT MONO (-5950 3025);
DISPLAY INVISIBLE (-5950 3025);
FORCEPROP 0 LAST CDS_SEC 1
J 0
(-5950 3025);
DISPLAY 1.021277 (-5950 3025);
DISPLAY INVISIBLE (-5950 3025);
FORCEPROP 1 LASTPIN (-6000 2975) $PN 1
J 0
(-5990 2955);
DISPLAY 0.489362 (-5990 2955);
PAINT MONO (-5990 2955);
FORCEPROP 1 LASTPIN (-6000 2775) $PN 2
J 0
(-5990 2755);
DISPLAY 0.489362 (-5990 2755);
PAINT MONO (-5990 2755);
FORCEPROP 1 LAST MATERIAL X7R
J 0
(-5950 2825);
DISPLAY 0.489362 (-5950 2825);
PAINT SKYBLUE (-5950 2825);
FORCEPROP 1 LAST PACK_TYPE 0402
J 0
(-5950 2725);
DISPLAY 0.489362 (-5950 2725);
PAINT SKYBLUE (-5950 2725);
FORCEPROP 1 LAST TOLERANCE 10%
J 0
(-5950 2875);
DISPLAY 0.489362 (-5950 2875);
PAINT SKYBLUE (-5950 2875);
FORCEPROP 1 LAST VALUE 0.1UF
J 0
(-5950 2975);
DISPLAY 0.489362 (-5950 2975);
PAINT SKYBLUE (-5950 2975);
FORCEPROP 1 LAST VOLTAGE 25V
J 0
(-5950 2925);
DISPLAY 0.489362 (-5950 2925);
PAINT SKYBLUE (-5950 2925);
FORCEPROP 2 LAST CDS_LIB pure_quanta
J 0
(-6000 2875);
DISPLAY INVISIBLE (-6000 2875);
FORCEPROP 1 LAST PATH I34
J 0
(-5950 3025);
DISPLAY 0.978723 (-5950 3025);
PAINT WHITE (-5950 3025);
DISPLAY INVISIBLE (-5950 3025);
FORCEPROP 1 LAST PART_NUMBER CH4104K1B00
J 0
(-5950 2775);
DISPLAY 0.489362 (-5950 2775);
PAINT SKYBLUE (-5950 2775);
DISPLAY INVISIBLE (-5950 2775);
FORCEADD UNIVERSAL_GND..1
(-5375 1025);
FORCEPROP 3 LASTPIN (-5375 1075) SIG_NAME GND\g
J 0
(-5365 1085);
DISPLAY 0.659574 (-5365 1085);
PAINT MONO (-5365 1085);
DISPLAY INVISIBLE (-5365 1085);
FORCEPROP 2 LAST CDS_LIB pure_quanta_power
J 0
(-5375 1025);
DISPLAY INVISIBLE (-5375 1025);
FORCEPROP 1 LAST HDL_POWER GND
J 1
(-5350 950);
DISPLAY 0.872340 (-5350 950);
PAINT GREEN (-5350 950);
DISPLAY INVISIBLE (-5350 950);
FORCEPROP 1 LAST PATH I35
J 0
(-5300 1025);
DISPLAY 0.872340 (-5300 1025);
PAINT AQUA (-5300 1025);
DISPLAY INVISIBLE (-5300 1025);
FORCEADD Q_RES..2
(-5375 1250);
FORCEPROP 1 LAST LOCATION PR513
J 0
(-5330 1375);
DISPLAY 0.489362 (-5330 1375);
PAINT SKYBLUE (-5330 1375);
FORCEPROP 0 LAST $SEC 1
J 0
(-5325 1425);
DISPLAY 0.680851 (-5325 1425);
PAINT MONO (-5325 1425);
DISPLAY INVISIBLE (-5325 1425);
FORCEPROP 0 LAST CDS_SEC 1
J 0
(-5325 1425);
DISPLAY 1.021277 (-5325 1425);
DISPLAY INVISIBLE (-5325 1425);
FORCEPROP 1 LASTPIN (-5375 1350) $PN 1
J 0
(-5370 1312);
DISPLAY 0.489362 (-5370 1312);
PAINT MONO (-5370 1312);
FORCEPROP 1 LASTPIN (-5375 1150) $PN 2
J 0
(-5370 1160);
DISPLAY 0.489362 (-5370 1160);
PAINT MONO (-5370 1160);
FORCEPROP 1 LAST TOLERANCE 1%
J 0
(-5330 1275);
DISPLAY 0.489362 (-5330 1275);
PAINT SKYBLUE (-5330 1275);
FORCEPROP 1 LAST WATTAGE 1/8W
J 0
(-5335 1225);
DISPLAY 0.489362 (-5335 1225);
PAINT SKYBLUE (-5335 1225);
FORCEPROP 1 LAST MATERIAL EMPTY
J 0
(-5335 1175);
DISPLAY 0.489362 (-5335 1175);
PAINT RED (-5335 1175);
FORCEPROP 1 LAST VALUE 1.5
J 0
(-5330 1325);
DISPLAY 0.489362 (-5330 1325);
PAINT SKYBLUE (-5330 1325);
FORCEPROP 1 LAST PACK_TYPE 0402LF
J 0
(-5335 1075);
DISPLAY 0.489362 (-5335 1075);
PAINT SKYBLUE (-5335 1075);
FORCEPROP 2 LAST CDS_LIB pure_quanta
J 0
(-5375 1250);
DISPLAY INVISIBLE (-5375 1250);
FORCEPROP 1 LAST PATH I36
J 0
(-5325 1425);
DISPLAY 0.978723 (-5325 1425);
PAINT WHITE (-5325 1425);
DISPLAY INVISIBLE (-5325 1425);
FORCEPROP 1 LAST PART_NUMBER CS-1504FB00
J 0
(-5335 1125);
DISPLAY 0.489362 (-5335 1125);
PAINT SKYBLUE (-5335 1125);
DISPLAY INVISIBLE (-5335 1125);
FORCEADD Q_CAP..1
(-5375 1800);
FORCEPROP 1 LAST LOCATION PC202
J 0
(-5325 1900);
DISPLAY 0.489362 (-5325 1900);
PAINT SKYBLUE (-5325 1900);
FORCEPROP 0 LAST $SEC 1
J 0
(-5325 1950);
DISPLAY 0.680851 (-5325 1950);
PAINT MONO (-5325 1950);
DISPLAY INVISIBLE (-5325 1950);
FORCEPROP 0 LAST CDS_SEC 1
J 0
(-5325 1950);
DISPLAY 1.021277 (-5325 1950);
DISPLAY INVISIBLE (-5325 1950);
FORCEPROP 1 LASTPIN (-5375 1900) $PN 1
J 0
(-5365 1880);
DISPLAY 0.489362 (-5365 1880);
PAINT MONO (-5365 1880);
FORCEPROP 1 LASTPIN (-5375 1700) $PN 2
J 0
(-5365 1680);
DISPLAY 0.489362 (-5365 1680);
PAINT MONO (-5365 1680);
FORCEPROP 1 LAST TOLERANCE 10%
J 0
(-5325 1750);
DISPLAY 0.489362 (-5325 1750);
PAINT SKYBLUE (-5325 1750);
FORCEPROP 1 LAST MATERIAL EMPTY
J 0
(-5325 1700);
DISPLAY 0.489362 (-5325 1700);
PAINT RED (-5325 1700);
FORCEPROP 1 LAST VALUE 560PF
J 0
(-5325 1850);
DISPLAY 0.489362 (-5325 1850);
PAINT SKYBLUE (-5325 1850);
FORCEPROP 1 LAST VOLTAGE 50V
J 0
(-5325 1800);
DISPLAY 0.489362 (-5325 1800);
PAINT SKYBLUE (-5325 1800);
FORCEPROP 1 LAST PACK_TYPE C0402
J 0
(-5325 1600);
DISPLAY 0.489362 (-5325 1600);
PAINT SKYBLUE (-5325 1600);
FORCEPROP 2 LAST CDS_LIB pure_quanta
J 0
(-5375 1800);
DISPLAY INVISIBLE (-5375 1800);
FORCEPROP 1 LAST PATH I37
J 0
(-5325 1950);
DISPLAY 0.978723 (-5325 1950);
PAINT WHITE (-5325 1950);
DISPLAY INVISIBLE (-5325 1950);
FORCEPROP 1 LAST PART_NUMBER CH1566K1B09
J 0
(-5325 1650);
DISPLAY 0.489362 (-5325 1650);
PAINT SKYBLUE (-5325 1650);
DISPLAY INVISIBLE (-5325 1650);
FORCEADD Q_RES..1
(-4500 750);
FORCEPROP 1 LAST LOCATION PR260
J 0
(-4550 775);
DISPLAY 0.489362 (-4550 775);
PAINT SKYBLUE (-4550 775);
FORCEPROP 0 LAST $SEC 1
J 0
(-4250 900);
DISPLAY 0.680851 (-4250 900);
PAINT MONO (-4250 900);
DISPLAY INVISIBLE (-4250 900);
FORCEPROP 0 LAST CDS_SEC 1
J 0
(-4250 900);
DISPLAY 1.021277 (-4250 900);
DISPLAY INVISIBLE (-4250 900);
FORCEPROP 1 LASTPIN (-4600 750) $PN 1
J 0
(-4588 762);
DISPLAY 0.489362 (-4588 762);
PAINT MONO (-4588 762);
FORCEPROP 1 LASTPIN (-4400 750) $PN 2
J 0
(-4438 762);
DISPLAY 0.489362 (-4438 762);
PAINT MONO (-4438 762);
FORCEPROP 1 LAST PACK_TYPE 0402LF
J 0
(-4400 700);
DISPLAY 0.489362 (-4400 700);
PAINT SKYBLUE (-4400 700);
FORCEPROP 1 LAST VALUE 0
J 2
(-4700 775);
DISPLAY 0.489362 (-4700 775);
PAINT SKYBLUE (-4700 775);
FORCEPROP 1 LAST TOLERANCE 5%
J 0
(-4675 775);
DISPLAY 0.489362 (-4675 775);
PAINT SKYBLUE (-4675 775);
FORCEPROP 1 LAST MATERIAL CHIP
J 0
(-4375 775);
DISPLAY 0.489362 (-4375 775);
PAINT SKYBLUE (-4375 775);
FORCEPROP 1 LAST WATTAGE 1/16W
J 2
(-4275 825);
DISPLAY 0.489362 (-4275 825);
PAINT SKYBLUE (-4275 825);
FORCEPROP 2 LAST CDS_LIB pure_quanta
J 0
(-4500 750);
DISPLAY INVISIBLE (-4500 750);
FORCEPROP 1 LAST PATH I38
J 0
(-4550 900);
DISPLAY 0.978723 (-4550 900);
PAINT WHITE (-4550 900);
DISPLAY INVISIBLE (-4550 900);
FORCEPROP 1 LAST PART_NUMBER CS00002JB13
J 0
(-4800 700);
DISPLAY 0.489362 (-4800 700);
PAINT SKYBLUE (-4800 700);
DISPLAY INVISIBLE (-4800 700);
FORCEADD OFFPAGE..6
(-4100 1725);
FORCEPROP 2 LAST $XR0 218 
J 0
(-4410 1725);
DISPLAY 0.638298 (-4410 1725);
PAINT MONO (-4410 1725);
FORCEPROP 2 LAST CDS_LIB standard
J 0
(-4100 1725);
DISPLAY INVISIBLE (-4100 1725);
FORCEPROP 1 LAST OFFPAGE TRUE
J 0
(-3775 1600);
DISPLAY 0.872340 (-3775 1600);
PAINT GREEN (-3775 1600);
DISPLAY INVISIBLE (-3775 1600);
FORCEPROP 1 LAST COMMENT_BODY TRUE
J 0
(-4000 1650);
DISPLAY 0.872340 (-4000 1650);
PAINT GREEN (-4000 1650);
DISPLAY INVISIBLE (-4000 1650);
FORCEPROP 2 LAST PATH I39
J 0
(-4400 1775);
DISPLAY 0.680851 (-4400 1775);
DISPLAY INVISIBLE (-4400 1775);
FORCEADD Q_RES..2
R 2
(-8750 1475);
FORCEPROP 1 LAST LOCATION PR254
J 2
(-8795 1600);
DISPLAY 0.489362 (-8795 1600);
PAINT SKYBLUE (-8795 1600);
FORCEPROP 0 LAST $SEC 1
J 0
(-8775 1650);
DISPLAY 0.680851 (-8775 1650);
PAINT MONO (-8775 1650);
DISPLAY INVISIBLE (-8775 1650);
FORCEPROP 0 LAST CDS_SEC 1
J 0
(-8775 1650);
DISPLAY 1.021277 (-8775 1650);
DISPLAY INVISIBLE (-8775 1650);
FORCEPROP 1 LASTPIN (-8750 1575) $PN 1
J 2
(-8755 1537);
DISPLAY 0.489362 (-8755 1537);
PAINT MONO (-8755 1537);
FORCEPROP 1 LASTPIN (-8750 1375) $PN 2
J 2
(-8755 1385);
DISPLAY 0.489362 (-8755 1385);
PAINT MONO (-8755 1385);
FORCEPROP 1 LAST WATTAGE 1/16W
J 2
(-8790 1450);
DISPLAY 0.489362 (-8790 1450);
PAINT SKYBLUE (-8790 1450);
FORCEPROP 1 LAST VALUE 8.87K
J 2
(-8795 1550);
DISPLAY 0.489362 (-8795 1550);
PAINT SKYBLUE (-8795 1550);
FORCEPROP 1 LAST MATERIAL EMPTY
J 2
(-8790 1400);
DISPLAY 0.489362 (-8790 1400);
PAINT RED (-8790 1400);
FORCEPROP 1 LAST TOLERANCE 1%
J 2
(-8795 1500);
DISPLAY 0.489362 (-8795 1500);
PAINT SKYBLUE (-8795 1500);
FORCEPROP 1 LAST PACK_TYPE 0402LF
J 2
(-8790 1300);
DISPLAY 0.489362 (-8790 1300);
PAINT SKYBLUE (-8790 1300);
FORCEPROP 2 LAST CDS_LIB pure_quanta
J 2
(-8750 1475);
DISPLAY INVISIBLE (-8750 1475);
FORCEPROP 1 LAST PATH I4
J 2
(-8800 1650);
DISPLAY 0.978723 (-8800 1650);
PAINT WHITE (-8800 1650);
DISPLAY INVISIBLE (-8800 1650);
FORCEPROP 1 LAST PART_NUMBER CS28872FB01
J 2
(-8790 1350);
DISPLAY 0.489362 (-8790 1350);
PAINT SKYBLUE (-8790 1350);
DISPLAY INVISIBLE (-8790 1350);
FORCEADD Q_CAP..1
(-4350 2200);
FORCEPROP 1 LAST LOCATION PC386
J 0
(-4300 2300);
DISPLAY 0.489362 (-4300 2300);
PAINT SKYBLUE (-4300 2300);
FORCEPROP 0 LAST $SEC 1
J 0
(-4300 2350);
DISPLAY 0.680851 (-4300 2350);
PAINT MONO (-4300 2350);
DISPLAY INVISIBLE (-4300 2350);
FORCEPROP 0 LAST CDS_SEC 1
J 2
(-4300 2325);
DISPLAY 1.021277 (-4300 2325);
DISPLAY INVISIBLE (-4300 2325);
FORCEPROP 1 LASTPIN (-4350 2300) $PN 1
J 0
(-4340 2280);
DISPLAY 0.489362 (-4340 2280);
PAINT MONO (-4340 2280);
FORCEPROP 1 LASTPIN (-4350 2100) $PN 2
J 0
(-4340 2080);
DISPLAY 0.489362 (-4340 2080);
PAINT MONO (-4340 2080);
FORCEPROP 1 LAST PACK_TYPE 0402
J 0
(-4300 2000);
DISPLAY 0.489362 (-4300 2000);
PAINT SKYBLUE (-4300 2000);
FORCEPROP 1 LAST MATERIAL X7R
J 0
(-4300 2100);
DISPLAY 0.489362 (-4300 2100);
PAINT SKYBLUE (-4300 2100);
FORCEPROP 1 LAST TOLERANCE 10%
J 0
(-4300 2150);
DISPLAY 0.489362 (-4300 2150);
PAINT SKYBLUE (-4300 2150);
FORCEPROP 1 LAST VOLTAGE 16V
J 0
(-4300 2200);
DISPLAY 0.489362 (-4300 2200);
PAINT SKYBLUE (-4300 2200);
FORCEPROP 1 LAST VALUE 0.22UF
J 0
(-4300 2250);
DISPLAY 0.489362 (-4300 2250);
PAINT SKYBLUE (-4300 2250);
FORCEPROP 2 LAST CDS_LIB pure_quanta
J 2
(-4350 2200);
DISPLAY INVISIBLE (-4350 2200);
FORCEPROP 1 LAST PATH I40
J 0
(-4300 2350);
DISPLAY 0.978723 (-4300 2350);
PAINT WHITE (-4300 2350);
DISPLAY INVISIBLE (-4300 2350);
FORCEPROP 1 LAST PART_NUMBER CH4223K1B00
J 0
(-4300 2050);
DISPLAY 0.489362 (-4300 2050);
PAINT SKYBLUE (-4300 2050);
DISPLAY INVISIBLE (-4300 2050);
FORCEADD Q_RES..1
(-5500 2325);
FORCEPROP 1 LAST LOCATION PR259
J 0
(-5725 2400);
DISPLAY 0.489362 (-5725 2400);
PAINT SKYBLUE (-5725 2400);
FORCEPROP 0 LAST $SEC 1
J 0
(-5225 2425);
DISPLAY 0.680851 (-5225 2425);
PAINT MONO (-5225 2425);
DISPLAY INVISIBLE (-5225 2425);
FORCEPROP 0 LAST CDS_SEC 1
J 0
(-5225 2425);
DISPLAY 1.021277 (-5225 2425);
DISPLAY INVISIBLE (-5225 2425);
FORCEPROP 1 LASTPIN (-5600 2325) $PN 1
J 0
(-5588 2337);
DISPLAY 0.787234 (-5588 2337);
PAINT MONO (-5588 2337);
DISPLAY INVISIBLE (-5588 2337);
FORCEPROP 1 LASTPIN (-5400 2325) $PN 2
J 0
(-5438 2337);
DISPLAY 0.787234 (-5438 2337);
PAINT MONO (-5438 2337);
DISPLAY INVISIBLE (-5438 2337);
FORCEPROP 1 LAST VALUE 5.6
J 2
(-5550 2400);
DISPLAY 0.489362 (-5550 2400);
PAINT SKYBLUE (-5550 2400);
FORCEPROP 1 LAST PACK_TYPE 0402LF
J 0
(-5100 2250);
DISPLAY 0.489362 (-5100 2250);
PAINT SKYBLUE (-5100 2250);
FORCEPROP 1 LAST WATTAGE 1/16W
J 2
(-5225 2400);
DISPLAY 0.489362 (-5225 2400);
PAINT SKYBLUE (-5225 2400);
FORCEPROP 1 LAST MATERIAL CHIP
J 0
(-5650 2250);
DISPLAY 0.489362 (-5650 2250);
PAINT SKYBLUE (-5650 2250);
FORCEPROP 1 LAST TOLERANCE 1%
J 0
(-5500 2400);
DISPLAY 0.489362 (-5500 2400);
PAINT SKYBLUE (-5500 2400);
FORCEPROP 2 LAST CDS_LIB pure_quanta
J 0
(-5500 2325);
DISPLAY INVISIBLE (-5500 2325);
FORCEPROP 1 LAST PATH I41
J 0
(-5550 2475);
DISPLAY 0.978723 (-5550 2475);
PAINT WHITE (-5550 2475);
DISPLAY INVISIBLE (-5550 2475);
FORCEPROP 1 LAST PART_NUMBER CS-5602FB01
J 0
(-5475 2250);
DISPLAY 0.489362 (-5475 2250);
PAINT SKYBLUE (-5475 2250);
DISPLAY INVISIBLE (-5475 2250);
FORCEADD Q_CAP..1
(-5600 2875);
FORCEPROP 1 LAST LOCATION PC378_2
J 0
(-5550 3025);
DISPLAY 0.489362 (-5550 3025);
PAINT SKYBLUE (-5550 3025);
FORCEPROP 0 LAST $SEC 1
J 0
(-5550 3075);
DISPLAY 0.680851 (-5550 3075);
PAINT MONO (-5550 3075);
DISPLAY INVISIBLE (-5550 3075);
FORCEPROP 0 LAST CDS_SEC 1
J 0
(-5550 3075);
DISPLAY 1.021277 (-5550 3075);
DISPLAY INVISIBLE (-5550 3075);
FORCEPROP 1 LASTPIN (-5600 2975) $PN 1
J 0
(-5590 2955);
DISPLAY 0.489362 (-5590 2955);
PAINT MONO (-5590 2955);
FORCEPROP 1 LASTPIN (-5600 2775) $PN 2
J 0
(-5590 2755);
DISPLAY 0.489362 (-5590 2755);
PAINT MONO (-5590 2755);
FORCEPROP 1 LAST MATERIAL X6S
J 0
(-5550 2825);
DISPLAY 0.489362 (-5550 2825);
PAINT SKYBLUE (-5550 2825);
FORCEPROP 1 LAST TOLERANCE 10%
J 0
(-5550 2875);
DISPLAY 0.489362 (-5550 2875);
PAINT SKYBLUE (-5550 2875);
FORCEPROP 1 LAST VOLTAGE 25V
J 0
(-5550 2925);
DISPLAY 0.489362 (-5550 2925);
PAINT SKYBLUE (-5550 2925);
FORCEPROP 1 LAST PACK_TYPE C0402
J 0
(-5550 2775);
DISPLAY 0.489362 (-5550 2775);
PAINT SKYBLUE (-5550 2775);
FORCEPROP 1 LAST VALUE 1UF
J 0
(-5550 2975);
DISPLAY 0.489362 (-5550 2975);
PAINT SKYBLUE (-5550 2975);
FORCEPROP 2 LAST CDS_LIB pure_quanta
J 0
(-5600 2875);
DISPLAY INVISIBLE (-5600 2875);
FORCEPROP 1 LAST PATH I42
J 0
(-5550 3025);
DISPLAY 0.978723 (-5550 3025);
PAINT WHITE (-5550 3025);
DISPLAY INVISIBLE (-5550 3025);
FORCEPROP 1 LAST PART_NUMBER CH5104KEB02
J 0
(-5550 2725);
DISPLAY 0.489362 (-5550 2725);
PAINT SKYBLUE (-5550 2725);
DISPLAY INVISIBLE (-5550 2725);
FORCEADD Q_CAP..1
(-5200 2875);
FORCEPROP 1 LAST LOCATION PC380_2
J 0
(-5150 3025);
DISPLAY 0.489362 (-5150 3025);
PAINT SKYBLUE (-5150 3025);
FORCEPROP 0 LAST $SEC 1
J 0
(-5150 3075);
DISPLAY 0.680851 (-5150 3075);
PAINT MONO (-5150 3075);
DISPLAY INVISIBLE (-5150 3075);
FORCEPROP 0 LAST CDS_SEC 1
J 0
(-5150 3075);
DISPLAY 1.021277 (-5150 3075);
DISPLAY INVISIBLE (-5150 3075);
FORCEPROP 1 LASTPIN (-5200 2975) $PN 1
J 0
(-5190 2955);
DISPLAY 0.489362 (-5190 2955);
PAINT MONO (-5190 2955);
FORCEPROP 1 LASTPIN (-5200 2775) $PN 2
J 0
(-5190 2755);
DISPLAY 0.489362 (-5190 2755);
PAINT MONO (-5190 2755);
FORCEPROP 1 LAST PACK_TYPE C0805
J 0
(-5150 2775);
DISPLAY 0.489362 (-5150 2775);
PAINT SKYBLUE (-5150 2775);
FORCEPROP 1 LAST MATERIAL X6S
J 0
(-5150 2825);
DISPLAY 0.489362 (-5150 2825);
PAINT SKYBLUE (-5150 2825);
FORCEPROP 1 LAST TOLERANCE 20%
J 0
(-5150 2875);
DISPLAY 0.489362 (-5150 2875);
PAINT SKYBLUE (-5150 2875);
FORCEPROP 1 LAST VALUE 22UF
J 0
(-5150 2975);
DISPLAY 0.489362 (-5150 2975);
PAINT SKYBLUE (-5150 2975);
FORCEPROP 1 LAST VOLTAGE 16V
J 0
(-5150 2925);
DISPLAY 0.489362 (-5150 2925);
PAINT SKYBLUE (-5150 2925);
FORCEPROP 2 LAST CDS_LIB pure_quanta
J 0
(-5200 2875);
DISPLAY INVISIBLE (-5200 2875);
FORCEPROP 1 LAST PATH I43
J 0
(-5150 3025);
DISPLAY 0.978723 (-5150 3025);
PAINT WHITE (-5150 3025);
DISPLAY INVISIBLE (-5150 3025);
FORCEPROP 1 LAST PART_NUMBER CH6223MEA01
J 0
(-5150 2725);
DISPLAY 0.489362 (-5150 2725);
PAINT SKYBLUE (-5150 2725);
DISPLAY INVISIBLE (-5150 2725);
FORCEADD UNIVERSAL_GND..1
(-5325 3650);
FORCEPROP 3 LASTPIN (-5325 3700) SIG_NAME GND\g
J 0
(-5315 3710);
DISPLAY 0.659574 (-5315 3710);
PAINT MONO (-5315 3710);
DISPLAY INVISIBLE (-5315 3710);
FORCEPROP 2 LAST CDS_LIB pure_quanta_power
J 0
(-5325 3650);
DISPLAY INVISIBLE (-5325 3650);
FORCEPROP 1 LAST HDL_POWER GND
J 1
(-5300 3575);
DISPLAY 0.872340 (-5300 3575);
PAINT GREEN (-5300 3575);
DISPLAY INVISIBLE (-5300 3575);
FORCEPROP 1 LAST PATH I44
J 0
(-5250 3650);
DISPLAY 0.872340 (-5250 3650);
PAINT AQUA (-5250 3650);
DISPLAY INVISIBLE (-5250 3650);
FORCEADD Q_RES..2
(-5325 3875);
FORCEPROP 1 LAST LOCATION PR512
J 0
(-5280 4000);
DISPLAY 0.489362 (-5280 4000);
PAINT SKYBLUE (-5280 4000);
FORCEPROP 0 LAST $SEC 1
J 0
(-5275 4050);
DISPLAY 0.680851 (-5275 4050);
PAINT MONO (-5275 4050);
DISPLAY INVISIBLE (-5275 4050);
FORCEPROP 0 LAST CDS_SEC 1
J 0
(-5275 4050);
DISPLAY 1.021277 (-5275 4050);
DISPLAY INVISIBLE (-5275 4050);
FORCEPROP 1 LASTPIN (-5325 3975) $PN 1
J 0
(-5320 3937);
DISPLAY 0.489362 (-5320 3937);
PAINT MONO (-5320 3937);
FORCEPROP 1 LASTPIN (-5325 3775) $PN 2
J 0
(-5320 3785);
DISPLAY 0.489362 (-5320 3785);
PAINT MONO (-5320 3785);
FORCEPROP 1 LAST WATTAGE 1/8W
J 0
(-5285 3850);
DISPLAY 0.489362 (-5285 3850);
PAINT SKYBLUE (-5285 3850);
FORCEPROP 1 LAST MATERIAL EMPTY
J 0
(-5285 3800);
DISPLAY 0.489362 (-5285 3800);
PAINT RED (-5285 3800);
FORCEPROP 1 LAST TOLERANCE 1%
J 0
(-5280 3900);
DISPLAY 0.489362 (-5280 3900);
PAINT SKYBLUE (-5280 3900);
FORCEPROP 1 LAST VALUE 1.5
J 0
(-5280 3950);
DISPLAY 0.489362 (-5280 3950);
PAINT SKYBLUE (-5280 3950);
FORCEPROP 1 LAST PACK_TYPE 0402LF
J 0
(-5285 3700);
DISPLAY 0.489362 (-5285 3700);
PAINT SKYBLUE (-5285 3700);
FORCEPROP 2 LAST CDS_LIB pure_quanta
J 0
(-5325 3875);
DISPLAY INVISIBLE (-5325 3875);
FORCEPROP 1 LAST PATH I45
J 0
(-5275 4050);
DISPLAY 0.978723 (-5275 4050);
PAINT WHITE (-5275 4050);
DISPLAY INVISIBLE (-5275 4050);
FORCEPROP 1 LAST PART_NUMBER CS-1504FB00
J 0
(-5285 3750);
DISPLAY 0.489362 (-5285 3750);
PAINT SKYBLUE (-5285 3750);
DISPLAY INVISIBLE (-5285 3750);
FORCEADD Q_CAP..1
(-4800 2875);
FORCEPROP 1 LAST LOCATION PC382_2
J 0
(-4750 3025);
DISPLAY 0.489362 (-4750 3025);
PAINT SKYBLUE (-4750 3025);
FORCEPROP 0 LAST $SEC 1
J 0
(-4750 3075);
DISPLAY 0.680851 (-4750 3075);
PAINT MONO (-4750 3075);
DISPLAY INVISIBLE (-4750 3075);
FORCEPROP 0 LAST CDS_SEC 1
J 0
(-4750 3075);
DISPLAY 1.021277 (-4750 3075);
DISPLAY INVISIBLE (-4750 3075);
FORCEPROP 1 LASTPIN (-4800 2975) $PN 1
J 0
(-4790 2955);
DISPLAY 0.489362 (-4790 2955);
PAINT MONO (-4790 2955);
FORCEPROP 1 LASTPIN (-4800 2775) $PN 2
J 0
(-4790 2755);
DISPLAY 0.489362 (-4790 2755);
PAINT MONO (-4790 2755);
FORCEPROP 1 LAST MATERIAL X6S
J 0
(-4750 2825);
DISPLAY 0.489362 (-4750 2825);
PAINT SKYBLUE (-4750 2825);
FORCEPROP 1 LAST VALUE 22UF
J 0
(-4750 2975);
DISPLAY 0.489362 (-4750 2975);
PAINT SKYBLUE (-4750 2975);
FORCEPROP 1 LAST VOLTAGE 16V
J 0
(-4750 2925);
DISPLAY 0.489362 (-4750 2925);
PAINT SKYBLUE (-4750 2925);
FORCEPROP 1 LAST TOLERANCE 20%
J 0
(-4750 2875);
DISPLAY 0.489362 (-4750 2875);
PAINT SKYBLUE (-4750 2875);
FORCEPROP 1 LAST PACK_TYPE C0805
J 0
(-4750 2775);
DISPLAY 0.489362 (-4750 2775);
PAINT SKYBLUE (-4750 2775);
FORCEPROP 2 LAST CDS_LIB pure_quanta
J 0
(-4800 2875);
DISPLAY INVISIBLE (-4800 2875);
FORCEPROP 1 LAST PATH I46
J 0
(-4750 3025);
DISPLAY 0.978723 (-4750 3025);
PAINT WHITE (-4750 3025);
DISPLAY INVISIBLE (-4750 3025);
FORCEPROP 1 LAST PART_NUMBER CH6223MEA01
J 0
(-4750 2725);
DISPLAY 0.489362 (-4750 2725);
PAINT SKYBLUE (-4750 2725);
DISPLAY INVISIBLE (-4750 2725);
FORCEADD UNIVERSAL_GND..1
(-4425 2500);
FORCEPROP 3 LASTPIN (-4425 2550) SIG_NAME GND\g
J 0
(-4415 2560);
DISPLAY 0.659574 (-4415 2560);
PAINT MONO (-4415 2560);
DISPLAY INVISIBLE (-4415 2560);
FORCEPROP 2 LAST CDS_LIB pure_quanta_power
J 0
(-4425 2500);
PAINT MONO (-4425 2500);
DISPLAY INVISIBLE (-4425 2500);
FORCEPROP 1 LAST HDL_POWER GND
J 1
(-4400 2425);
DISPLAY 0.872340 (-4400 2425);
PAINT GREEN (-4400 2425);
DISPLAY INVISIBLE (-4400 2425);
FORCEPROP 1 LAST PATH I47
J 0
(-4350 2500);
DISPLAY 0.872340 (-4350 2500);
PAINT AQUA (-4350 2500);
DISPLAY INVISIBLE (-4350 2500);
FORCEADD Q_CAP..1
(-4425 2875);
FORCEPROP 1 LAST LOCATION PC385_2
J 0
(-4375 3025);
DISPLAY 0.489362 (-4375 3025);
PAINT SKYBLUE (-4375 3025);
FORCEPROP 0 LAST $SEC 1
J 0
(-4375 3075);
DISPLAY 0.680851 (-4375 3075);
PAINT MONO (-4375 3075);
DISPLAY INVISIBLE (-4375 3075);
FORCEPROP 0 LAST CDS_SEC 1
J 0
(-4375 3075);
DISPLAY 1.021277 (-4375 3075);
DISPLAY INVISIBLE (-4375 3075);
FORCEPROP 1 LASTPIN (-4425 2975) $PN 1
J 0
(-4415 2955);
DISPLAY 0.489362 (-4415 2955);
PAINT MONO (-4415 2955);
FORCEPROP 1 LASTPIN (-4425 2775) $PN 2
J 0
(-4415 2755);
DISPLAY 0.489362 (-4415 2755);
PAINT MONO (-4415 2755);
FORCEPROP 1 LAST VALUE 22UF
J 0
(-4375 2975);
DISPLAY 0.489362 (-4375 2975);
PAINT SKYBLUE (-4375 2975);
FORCEPROP 1 LAST VOLTAGE 16V
J 0
(-4375 2925);
DISPLAY 0.489362 (-4375 2925);
PAINT SKYBLUE (-4375 2925);
FORCEPROP 1 LAST PACK_TYPE C0805
J 0
(-4375 2775);
DISPLAY 0.489362 (-4375 2775);
PAINT SKYBLUE (-4375 2775);
FORCEPROP 1 LAST MATERIAL X6S
J 0
(-4375 2825);
DISPLAY 0.489362 (-4375 2825);
PAINT SKYBLUE (-4375 2825);
FORCEPROP 1 LAST TOLERANCE 20%
J 0
(-4375 2875);
DISPLAY 0.489362 (-4375 2875);
PAINT SKYBLUE (-4375 2875);
FORCEPROP 2 LAST CDS_LIB pure_quanta
J 0
(-4425 2875);
DISPLAY INVISIBLE (-4425 2875);
FORCEPROP 1 LAST PATH I48
J 0
(-4375 3025);
DISPLAY 0.978723 (-4375 3025);
PAINT WHITE (-4375 3025);
DISPLAY INVISIBLE (-4375 3025);
FORCEPROP 1 LAST PART_NUMBER CH6223MEA01
J 0
(-4375 2725);
DISPLAY 0.489362 (-4375 2725);
PAINT SKYBLUE (-4375 2725);
DISPLAY INVISIBLE (-4375 2725);
FORCEADD VCC_CORE..1
(-4425 3225);
FORCEPROP 3 LASTPIN (-4425 3175) SIG_NAME SW_P12V_AUX_PVDDCR_CPU1_P1_FLT\g
J 0
(-4415 3185);
DISPLAY 0.659574 (-4415 3185);
PAINT MONO (-4415 3185);
DISPLAY INVISIBLE (-4415 3185);
FORCEPROP 1 LAST HDL_POWER SW_P12V_AUX_PVDDCR_CPU1_P1_FLT
J 1
(-4425 3275);
DISPLAY 0.489362 (-4425 3275);
PAINT GREEN (-4425 3275);
FORCEPROP 2 LAST CDS_LIB pure_quanta_power
J 0
(-4425 3225);
DISPLAY INVISIBLE (-4425 3225);
FORCEPROP 1 LAST PATH I49
J 0
(-4375 3250);
DISPLAY 0.872340 (-4375 3250);
PAINT AQUA (-4375 3250);
DISPLAY INVISIBLE (-4375 3250);
FORCEADD OFFPAGE..1
(-8200 1375);
FORCEPROP 2 LAST $XR0 217 
J 0
(-8452 1375);
DISPLAY 0.638298 (-8452 1375);
PAINT MONO (-8452 1375);
FORCEPROP 2 LAST CDS_LIB standard
J 0
(-8200 1375);
DISPLAY INVISIBLE (-8200 1375);
FORCEPROP 1 LAST OFFPAGE TRUE
J 0
(-7875 1250);
DISPLAY 0.872340 (-7875 1250);
PAINT GREEN (-7875 1250);
DISPLAY INVISIBLE (-7875 1250);
FORCEPROP 1 LAST COMMENT_BODY TRUE
J 0
(-8075 1275);
DISPLAY 0.872340 (-8075 1275);
PAINT GREEN (-8075 1275);
DISPLAY INVISIBLE (-8075 1275);
FORCEPROP 2 LAST PATH I5
J 0
(-8450 1425);
DISPLAY 0.680851 (-8450 1425);
DISPLAY INVISIBLE (-8450 1425);
FORCEADD Q_CAP..1
(-6025 5500);
FORCEPROP 1 LAST LOCATION PC375_1
J 0
(-5975 5650);
DISPLAY 0.489362 (-5975 5650);
PAINT SKYBLUE (-5975 5650);
FORCEPROP 0 LAST $SEC 1
J 0
(-5975 5650);
DISPLAY 0.680851 (-5975 5650);
PAINT MONO (-5975 5650);
DISPLAY INVISIBLE (-5975 5650);
FORCEPROP 0 LAST CDS_SEC 1
J 0
(-5975 5650);
DISPLAY 1.021277 (-5975 5650);
DISPLAY INVISIBLE (-5975 5650);
FORCEPROP 1 LASTPIN (-6025 5600) $PN 1
J 0
(-6015 5580);
DISPLAY 0.489362 (-6015 5580);
PAINT MONO (-6015 5580);
FORCEPROP 1 LASTPIN (-6025 5400) $PN 2
J 0
(-6015 5380);
DISPLAY 0.489362 (-6015 5380);
PAINT MONO (-6015 5380);
FORCEPROP 1 LAST PACK_TYPE 0402
J 0
(-5975 5400);
DISPLAY 0.489362 (-5975 5400);
PAINT SKYBLUE (-5975 5400);
FORCEPROP 1 LAST MATERIAL X7R
J 0
(-5975 5450);
DISPLAY 0.489362 (-5975 5450);
PAINT SKYBLUE (-5975 5450);
FORCEPROP 1 LAST TOLERANCE 10%
J 0
(-5975 5500);
DISPLAY 0.489362 (-5975 5500);
PAINT SKYBLUE (-5975 5500);
FORCEPROP 1 LAST VALUE 0.1UF
J 0
(-5975 5600);
DISPLAY 0.489362 (-5975 5600);
PAINT SKYBLUE (-5975 5600);
FORCEPROP 1 LAST VOLTAGE 25V
J 0
(-5975 5550);
DISPLAY 0.489362 (-5975 5550);
PAINT SKYBLUE (-5975 5550);
FORCEPROP 2 LAST CDS_LIB pure_quanta
J 0
(-6025 5500);
DISPLAY INVISIBLE (-6025 5500);
FORCEPROP 1 LAST PATH I50
J 0
(-5975 5650);
DISPLAY 0.978723 (-5975 5650);
PAINT WHITE (-5975 5650);
DISPLAY INVISIBLE (-5975 5650);
FORCEPROP 1 LAST PART_NUMBER CH4104K1B00
J 0
(-5975 5350);
DISPLAY 0.489362 (-5975 5350);
PAINT SKYBLUE (-5975 5350);
DISPLAY INVISIBLE (-5975 5350);
FORCEADD Q_RES..1
(-5550 4950);
FORCEPROP 1 LAST LOCATION PR258
J 0
(-5450 4950);
DISPLAY 0.489362 (-5450 4950);
PAINT SKYBLUE (-5450 4950);
FORCEPROP 0 LAST $SEC 1
J 0
(-5675 5100);
DISPLAY 0.680851 (-5675 5100);
PAINT MONO (-5675 5100);
DISPLAY INVISIBLE (-5675 5100);
FORCEPROP 0 LAST CDS_SEC 1
J 0
(-5675 5100);
DISPLAY 1.021277 (-5675 5100);
DISPLAY INVISIBLE (-5675 5100);
FORCEPROP 1 LASTPIN (-5650 4950) $PN 1
J 0
(-5638 4962);
DISPLAY 0.787234 (-5638 4962);
PAINT MONO (-5638 4962);
DISPLAY INVISIBLE (-5638 4962);
FORCEPROP 1 LASTPIN (-5450 4950) $PN 2
J 0
(-5488 4962);
DISPLAY 0.787234 (-5488 4962);
PAINT MONO (-5488 4962);
DISPLAY INVISIBLE (-5488 4962);
FORCEPROP 1 LAST PACK_TYPE 0402LF
J 0
(-5700 4800);
DISPLAY 0.489362 (-5700 4800);
PAINT SKYBLUE (-5700 4800);
FORCEPROP 1 LAST WATTAGE 1/16W
J 0
(-5700 4825);
DISPLAY 0.489362 (-5700 4825);
PAINT SKYBLUE (-5700 4825);
FORCEPROP 1 LAST VALUE 5.6
J 2
(-5625 4950);
DISPLAY 0.489362 (-5625 4950);
PAINT SKYBLUE (-5625 4950);
FORCEPROP 1 LAST TOLERANCE 1%
J 0
(-5700 4850);
DISPLAY 0.489362 (-5700 4850);
PAINT SKYBLUE (-5700 4850);
FORCEPROP 1 LAST MATERIAL CHIP
J 0
(-5700 4875);
DISPLAY 0.489362 (-5700 4875);
PAINT SKYBLUE (-5700 4875);
FORCEPROP 2 LAST CDS_LIB pure_quanta
J 0
(-5550 4950);
DISPLAY INVISIBLE (-5550 4950);
FORCEPROP 1 LAST PATH I51
J 0
(-5600 5100);
DISPLAY 0.978723 (-5600 5100);
PAINT WHITE (-5600 5100);
DISPLAY INVISIBLE (-5600 5100);
FORCEPROP 1 LAST PART_NUMBER CS-5602FB01
J 0
(-5700 4900);
DISPLAY 0.489362 (-5700 4900);
PAINT SKYBLUE (-5700 4900);
DISPLAY INVISIBLE (-5700 4900);
FORCEADD Q_CAP..1
(-5325 4400);
FORCEPROP 1 LAST LOCATION PC201
J 0
(-5275 4500);
DISPLAY 0.489362 (-5275 4500);
PAINT SKYBLUE (-5275 4500);
FORCEPROP 0 LAST $SEC 1
J 0
(-5275 4550);
DISPLAY 0.680851 (-5275 4550);
PAINT MONO (-5275 4550);
DISPLAY INVISIBLE (-5275 4550);
FORCEPROP 0 LAST CDS_SEC 1
J 0
(-5275 4550);
DISPLAY 1.021277 (-5275 4550);
DISPLAY INVISIBLE (-5275 4550);
FORCEPROP 1 LASTPIN (-5325 4500) $PN 1
J 0
(-5315 4480);
DISPLAY 0.489362 (-5315 4480);
PAINT MONO (-5315 4480);
FORCEPROP 1 LASTPIN (-5325 4300) $PN 2
J 0
(-5315 4280);
DISPLAY 0.489362 (-5315 4280);
PAINT MONO (-5315 4280);
FORCEPROP 1 LAST MATERIAL EMPTY
J 0
(-5275 4300);
DISPLAY 0.489362 (-5275 4300);
PAINT RED (-5275 4300);
FORCEPROP 1 LAST TOLERANCE 10%
J 0
(-5275 4350);
DISPLAY 0.489362 (-5275 4350);
PAINT SKYBLUE (-5275 4350);
FORCEPROP 1 LAST VALUE 560PF
J 0
(-5275 4450);
DISPLAY 0.489362 (-5275 4450);
PAINT SKYBLUE (-5275 4450);
FORCEPROP 1 LAST VOLTAGE 50V
J 0
(-5275 4400);
DISPLAY 0.489362 (-5275 4400);
PAINT SKYBLUE (-5275 4400);
FORCEPROP 1 LAST PACK_TYPE C0402
J 0
(-5275 4200);
DISPLAY 0.489362 (-5275 4200);
PAINT SKYBLUE (-5275 4200);
FORCEPROP 2 LAST CDS_LIB pure_quanta
J 0
(-5325 4400);
DISPLAY INVISIBLE (-5325 4400);
FORCEPROP 1 LAST PATH I52
J 0
(-5275 4550);
DISPLAY 0.978723 (-5275 4550);
PAINT WHITE (-5275 4550);
DISPLAY INVISIBLE (-5275 4550);
FORCEPROP 1 LAST PART_NUMBER CH1566K1B09
J 0
(-5275 4250);
DISPLAY 0.489362 (-5275 4250);
PAINT SKYBLUE (-5275 4250);
DISPLAY INVISIBLE (-5275 4250);
FORCEADD Q_CAP..1
(-5625 5500);
FORCEPROP 1 LAST LOCATION PC377_1
J 0
(-5575 5650);
DISPLAY 0.489362 (-5575 5650);
PAINT SKYBLUE (-5575 5650);
FORCEPROP 0 LAST $SEC 1
J 0
(-5575 5700);
DISPLAY 0.680851 (-5575 5700);
PAINT MONO (-5575 5700);
DISPLAY INVISIBLE (-5575 5700);
FORCEPROP 0 LAST CDS_SEC 1
J 0
(-5575 5700);
DISPLAY 1.021277 (-5575 5700);
DISPLAY INVISIBLE (-5575 5700);
FORCEPROP 1 LASTPIN (-5625 5600) $PN 1
J 0
(-5615 5580);
DISPLAY 0.489362 (-5615 5580);
PAINT MONO (-5615 5580);
FORCEPROP 1 LASTPIN (-5625 5400) $PN 2
J 0
(-5615 5380);
DISPLAY 0.489362 (-5615 5380);
PAINT MONO (-5615 5380);
FORCEPROP 1 LAST TOLERANCE 10%
J 0
(-5575 5500);
DISPLAY 0.489362 (-5575 5500);
PAINT SKYBLUE (-5575 5500);
FORCEPROP 1 LAST MATERIAL X6S
J 0
(-5575 5450);
DISPLAY 0.489362 (-5575 5450);
PAINT SKYBLUE (-5575 5450);
FORCEPROP 1 LAST VALUE 1UF
J 0
(-5575 5600);
DISPLAY 0.489362 (-5575 5600);
PAINT SKYBLUE (-5575 5600);
FORCEPROP 1 LAST VOLTAGE 25V
J 0
(-5575 5550);
DISPLAY 0.489362 (-5575 5550);
PAINT SKYBLUE (-5575 5550);
FORCEPROP 1 LAST PACK_TYPE C0402
J 0
(-5575 5400);
DISPLAY 0.489362 (-5575 5400);
PAINT SKYBLUE (-5575 5400);
FORCEPROP 2 LAST CDS_LIB pure_quanta
J 0
(-5625 5500);
DISPLAY INVISIBLE (-5625 5500);
FORCEPROP 1 LAST PATH I53
J 0
(-5575 5650);
DISPLAY 0.978723 (-5575 5650);
PAINT WHITE (-5575 5650);
DISPLAY INVISIBLE (-5575 5650);
FORCEPROP 1 LAST PART_NUMBER CH5104KEB02
J 0
(-5575 5350);
DISPLAY 0.489362 (-5575 5350);
PAINT SKYBLUE (-5575 5350);
DISPLAY INVISIBLE (-5575 5350);
FORCEADD Q_CAP..1
(-5225 5500);
FORCEPROP 1 LAST LOCATION PC379_1
J 0
(-5175 5650);
DISPLAY 0.489362 (-5175 5650);
PAINT SKYBLUE (-5175 5650);
FORCEPROP 0 LAST $SEC 1
J 0
(-5175 5700);
DISPLAY 0.680851 (-5175 5700);
PAINT MONO (-5175 5700);
DISPLAY INVISIBLE (-5175 5700);
FORCEPROP 0 LAST CDS_SEC 1
J 0
(-5175 5700);
DISPLAY 1.021277 (-5175 5700);
DISPLAY INVISIBLE (-5175 5700);
FORCEPROP 1 LASTPIN (-5225 5600) $PN 1
J 0
(-5215 5580);
DISPLAY 0.489362 (-5215 5580);
PAINT MONO (-5215 5580);
FORCEPROP 1 LASTPIN (-5225 5400) $PN 2
J 0
(-5215 5380);
DISPLAY 0.489362 (-5215 5380);
PAINT MONO (-5215 5380);
FORCEPROP 1 LAST PACK_TYPE C0805
J 0
(-5175 5400);
DISPLAY 0.489362 (-5175 5400);
PAINT SKYBLUE (-5175 5400);
FORCEPROP 1 LAST MATERIAL X6S
J 0
(-5175 5450);
DISPLAY 0.489362 (-5175 5450);
PAINT SKYBLUE (-5175 5450);
FORCEPROP 1 LAST VALUE 22UF
J 0
(-5175 5600);
DISPLAY 0.489362 (-5175 5600);
PAINT SKYBLUE (-5175 5600);
FORCEPROP 1 LAST VOLTAGE 16V
J 0
(-5175 5550);
DISPLAY 0.489362 (-5175 5550);
PAINT SKYBLUE (-5175 5550);
FORCEPROP 1 LAST TOLERANCE 20%
J 0
(-5175 5500);
DISPLAY 0.489362 (-5175 5500);
PAINT SKYBLUE (-5175 5500);
FORCEPROP 2 LAST CDS_LIB pure_quanta
J 0
(-5225 5500);
DISPLAY INVISIBLE (-5225 5500);
FORCEPROP 1 LAST PATH I54
J 0
(-5175 5650);
DISPLAY 0.978723 (-5175 5650);
PAINT WHITE (-5175 5650);
DISPLAY INVISIBLE (-5175 5650);
FORCEPROP 1 LAST PART_NUMBER CH6223MEA01
J 0
(-5175 5350);
DISPLAY 0.489362 (-5175 5350);
PAINT SKYBLUE (-5175 5350);
DISPLAY INVISIBLE (-5175 5350);
FORCEADD OFFPAGE..6
(-4550 4350);
FORCEPROP 2 LAST $XR0 220 
J 0
(-4860 4350);
DISPLAY 0.638298 (-4860 4350);
PAINT MONO (-4860 4350);
FORCEPROP 2 LAST CDS_LIB standard
J 2
(-4550 4350);
DISPLAY INVISIBLE (-4550 4350);
FORCEPROP 1 LAST OFFPAGE TRUE
J 0
(-4225 4225);
DISPLAY 0.872340 (-4225 4225);
PAINT GREEN (-4225 4225);
DISPLAY INVISIBLE (-4225 4225);
FORCEPROP 1 LAST COMMENT_BODY TRUE
J 0
(-4450 4275);
DISPLAY 0.872340 (-4450 4275);
PAINT GREEN (-4450 4275);
DISPLAY INVISIBLE (-4450 4275);
FORCEPROP 2 LAST PATH I55
J 0
(-4850 4400);
DISPLAY 0.680851 (-4850 4400);
DISPLAY INVISIBLE (-4850 4400);
FORCEADD UNIVERSAL_GND..1
(-4575 5100);
FORCEPROP 3 LASTPIN (-4575 5150) SIG_NAME GND\g
J 0
(-4565 5160);
DISPLAY 0.659574 (-4565 5160);
PAINT MONO (-4565 5160);
DISPLAY INVISIBLE (-4565 5160);
FORCEPROP 2 LAST CDS_LIB pure_quanta_power
J 0
(-4575 5100);
PAINT MONO (-4575 5100);
DISPLAY INVISIBLE (-4575 5100);
FORCEPROP 1 LAST HDL_POWER GND
J 1
(-4550 5025);
DISPLAY 0.872340 (-4550 5025);
PAINT GREEN (-4550 5025);
DISPLAY INVISIBLE (-4550 5025);
FORCEPROP 1 LAST PATH I56
J 0
(-4500 5100);
DISPLAY 0.872340 (-4500 5100);
PAINT AQUA (-4500 5100);
DISPLAY INVISIBLE (-4500 5100);
FORCEADD Q_CAP..1
(-4475 4825);
FORCEPROP 1 LAST LOCATION PC383
J 0
(-4425 4925);
DISPLAY 0.489362 (-4425 4925);
PAINT SKYBLUE (-4425 4925);
FORCEPROP 0 LAST $SEC 1
J 0
(-4425 4975);
DISPLAY 0.680851 (-4425 4975);
PAINT MONO (-4425 4975);
DISPLAY INVISIBLE (-4425 4975);
FORCEPROP 0 LAST CDS_SEC 1
J 0
(-4425 4975);
DISPLAY 1.021277 (-4425 4975);
DISPLAY INVISIBLE (-4425 4975);
FORCEPROP 1 LASTPIN (-4475 4925) $PN 1
J 0
(-4465 4905);
DISPLAY 0.489362 (-4465 4905);
PAINT MONO (-4465 4905);
FORCEPROP 1 LASTPIN (-4475 4725) $PN 2
J 0
(-4465 4705);
DISPLAY 0.489362 (-4465 4705);
PAINT MONO (-4465 4705);
FORCEPROP 1 LAST MATERIAL X7R
J 0
(-4425 4725);
DISPLAY 0.489362 (-4425 4725);
PAINT SKYBLUE (-4425 4725);
FORCEPROP 1 LAST PACK_TYPE 0402
J 0
(-4425 4625);
DISPLAY 0.489362 (-4425 4625);
PAINT SKYBLUE (-4425 4625);
FORCEPROP 1 LAST TOLERANCE 10%
J 0
(-4425 4775);
DISPLAY 0.489362 (-4425 4775);
PAINT SKYBLUE (-4425 4775);
FORCEPROP 1 LAST VOLTAGE 16V
J 0
(-4425 4825);
DISPLAY 0.489362 (-4425 4825);
PAINT SKYBLUE (-4425 4825);
FORCEPROP 1 LAST VALUE 0.22UF
J 0
(-4425 4875);
DISPLAY 0.489362 (-4425 4875);
PAINT SKYBLUE (-4425 4875);
FORCEPROP 2 LAST CDS_LIB pure_quanta
J 2
(-4475 4825);
DISPLAY INVISIBLE (-4475 4825);
FORCEPROP 1 LAST PATH I57
J 0
(-4425 4975);
DISPLAY 0.978723 (-4425 4975);
PAINT WHITE (-4425 4975);
DISPLAY INVISIBLE (-4425 4975);
FORCEPROP 1 LAST PART_NUMBER CH4223K1B00
J 0
(-4425 4675);
DISPLAY 0.489362 (-4425 4675);
PAINT SKYBLUE (-4425 4675);
DISPLAY INVISIBLE (-4425 4675);
FORCEADD Q_CAP..1
(-4825 5500);
FORCEPROP 1 LAST LOCATION PC381_1
J 0
(-4775 5650);
DISPLAY 0.489362 (-4775 5650);
PAINT SKYBLUE (-4775 5650);
FORCEPROP 0 LAST $SEC 1
J 0
(-4775 5700);
DISPLAY 0.680851 (-4775 5700);
PAINT MONO (-4775 5700);
DISPLAY INVISIBLE (-4775 5700);
FORCEPROP 0 LAST CDS_SEC 1
J 0
(-4775 5700);
DISPLAY 1.021277 (-4775 5700);
DISPLAY INVISIBLE (-4775 5700);
FORCEPROP 1 LASTPIN (-4825 5600) $PN 1
J 0
(-4815 5580);
DISPLAY 0.489362 (-4815 5580);
PAINT MONO (-4815 5580);
FORCEPROP 1 LASTPIN (-4825 5400) $PN 2
J 0
(-4815 5380);
DISPLAY 0.489362 (-4815 5380);
PAINT MONO (-4815 5380);
FORCEPROP 1 LAST TOLERANCE 20%
J 0
(-4775 5500);
DISPLAY 0.489362 (-4775 5500);
PAINT SKYBLUE (-4775 5500);
FORCEPROP 1 LAST PACK_TYPE C0805
J 0
(-4775 5400);
DISPLAY 0.489362 (-4775 5400);
PAINT SKYBLUE (-4775 5400);
FORCEPROP 1 LAST VALUE 22UF
J 0
(-4775 5600);
DISPLAY 0.489362 (-4775 5600);
PAINT SKYBLUE (-4775 5600);
FORCEPROP 1 LAST VOLTAGE 16V
J 0
(-4775 5550);
DISPLAY 0.489362 (-4775 5550);
PAINT SKYBLUE (-4775 5550);
FORCEPROP 1 LAST MATERIAL X6S
J 0
(-4775 5450);
DISPLAY 0.489362 (-4775 5450);
PAINT SKYBLUE (-4775 5450);
FORCEPROP 2 LAST CDS_LIB pure_quanta
J 0
(-4825 5500);
DISPLAY INVISIBLE (-4825 5500);
FORCEPROP 1 LAST PATH I58
J 0
(-4775 5650);
DISPLAY 0.978723 (-4775 5650);
PAINT WHITE (-4775 5650);
DISPLAY INVISIBLE (-4775 5650);
FORCEPROP 1 LAST PART_NUMBER CH6223MEA01
J 0
(-4775 5350);
DISPLAY 0.489362 (-4775 5350);
PAINT SKYBLUE (-4775 5350);
DISPLAY INVISIBLE (-4775 5350);
FORCEADD VCC_CORE..1
(-4625 5900);
FORCEPROP 3 LASTPIN (-4625 5850) SIG_NAME SW_P12V_AUX_PVDDCR_CPU1_P1_FLT\g
J 0
(-4615 5860);
DISPLAY 0.659574 (-4615 5860);
PAINT MONO (-4615 5860);
DISPLAY INVISIBLE (-4615 5860);
FORCEPROP 1 LAST HDL_POWER SW_P12V_AUX_PVDDCR_CPU1_P1_FLT
J 1
(-4625 5950);
DISPLAY 0.489362 (-4625 5950);
PAINT GREEN (-4625 5950);
FORCEPROP 2 LAST CDS_LIB pure_quanta_power
J 0
(-4625 5900);
DISPLAY INVISIBLE (-4625 5900);
FORCEPROP 1 LAST PATH I59
J 0
(-4575 5925);
DISPLAY 0.872340 (-4575 5925);
PAINT AQUA (-4575 5925);
DISPLAY INVISIBLE (-4575 5925);
FORCEADD OFFPAGE..5
(-8200 1475);
FORCEPROP 2 LAST $XR3 217 
J 0
(-8575 1439);
DISPLAY 0.638298 (-8575 1439);
PAINT MONO (-8575 1439);
FORCEPROP 2 LAST $XR1 219 
J 0
(-8575 1475);
DISPLAY 0.638298 (-8575 1475);
PAINT MONO (-8575 1475);
FORCEPROP 2 LAST $XR0 218 
J 0
(-8455 1475);
DISPLAY 0.638298 (-8455 1475);
PAINT MONO (-8455 1475);
FORCEPROP 2 LAST $XR2 220 
J 0
(-8455 1439);
DISPLAY 0.638298 (-8455 1439);
PAINT MONO (-8455 1439);
FORCEPROP 2 LAST CDS_LIB standard
J 0
(-8200 1475);
DISPLAY INVISIBLE (-8200 1475);
FORCEPROP 1 LAST OFFPAGE TRUE
J 0
(-7875 1350);
DISPLAY 0.872340 (-7875 1350);
PAINT GREEN (-7875 1350);
DISPLAY INVISIBLE (-7875 1350);
FORCEPROP 1 LAST COMMENT_BODY TRUE
J 0
(-8100 1400);
DISPLAY 0.872340 (-8100 1400);
PAINT GREEN (-8100 1400);
DISPLAY INVISIBLE (-8100 1400);
FORCEPROP 2 LAST PATH I6
J 0
(-8450 1525);
DISPLAY 0.680851 (-8450 1525);
DISPLAY INVISIBLE (-8450 1525);
FORCEADD Q_CAP..1
(-4450 5500);
FORCEPROP 1 LAST LOCATION PC384_1
J 0
(-4400 5650);
DISPLAY 0.489362 (-4400 5650);
PAINT SKYBLUE (-4400 5650);
FORCEPROP 0 LAST $SEC 1
J 0
(-4400 5700);
DISPLAY 0.680851 (-4400 5700);
PAINT MONO (-4400 5700);
DISPLAY INVISIBLE (-4400 5700);
FORCEPROP 0 LAST CDS_SEC 1
J 0
(-4400 5700);
DISPLAY 1.021277 (-4400 5700);
DISPLAY INVISIBLE (-4400 5700);
FORCEPROP 1 LASTPIN (-4450 5600) $PN 1
J 0
(-4440 5580);
DISPLAY 0.489362 (-4440 5580);
PAINT MONO (-4440 5580);
FORCEPROP 1 LASTPIN (-4450 5400) $PN 2
J 0
(-4440 5380);
DISPLAY 0.489362 (-4440 5380);
PAINT MONO (-4440 5380);
FORCEPROP 1 LAST VALUE 22UF
J 0
(-4400 5600);
DISPLAY 0.489362 (-4400 5600);
PAINT SKYBLUE (-4400 5600);
FORCEPROP 1 LAST TOLERANCE 20%
J 0
(-4400 5500);
DISPLAY 0.489362 (-4400 5500);
PAINT SKYBLUE (-4400 5500);
FORCEPROP 1 LAST PACK_TYPE C0805
J 0
(-4400 5400);
DISPLAY 0.489362 (-4400 5400);
PAINT SKYBLUE (-4400 5400);
FORCEPROP 1 LAST MATERIAL X6S
J 0
(-4400 5450);
DISPLAY 0.489362 (-4400 5450);
PAINT SKYBLUE (-4400 5450);
FORCEPROP 1 LAST VOLTAGE 16V
J 0
(-4400 5550);
DISPLAY 0.489362 (-4400 5550);
PAINT SKYBLUE (-4400 5550);
FORCEPROP 2 LAST CDS_LIB pure_quanta
J 0
(-4450 5500);
DISPLAY INVISIBLE (-4450 5500);
FORCEPROP 1 LAST PATH I60
J 0
(-4400 5650);
DISPLAY 0.978723 (-4400 5650);
PAINT WHITE (-4400 5650);
DISPLAY INVISIBLE (-4400 5650);
FORCEPROP 1 LAST PART_NUMBER CH6223MEA01
J 0
(-4400 5350);
DISPLAY 0.489362 (-4400 5350);
PAINT SKYBLUE (-4400 5350);
DISPLAY INVISIBLE (-4400 5350);
FORCEADD Q_INDUCTOR4P_14..1
(-3050 1850);
FORCEPROP 1 LAST LOCATION PL41
J 0
(-3275 2105);
DISPLAY 0.489362 (-3275 2105);
PAINT SKYBLUE (-3275 2105);
FORCEPROP 0 LAST $SEC 1
J 0
(-3275 2150);
DISPLAY 0.680851 (-3275 2150);
PAINT MONO (-3275 2150);
DISPLAY INVISIBLE (-3275 2150);
FORCEPROP 0 LAST CDS_SEC 1
J 0
(-3275 2150);
DISPLAY 1.021277 (-3275 2150);
DISPLAY INVISIBLE (-3275 2150);
FORCEPROP 0 LASTPIN (-3450 1975) $PN 1
J 2
(-3460 1985);
DISPLAY 0.489362 (-3460 1985);
PAINT MONO (-3460 1985);
FORCEPROP 0 LASTPIN (-3450 1725) $PN 2
J 2
(-3460 1735);
DISPLAY 0.489362 (-3460 1735);
PAINT MONO (-3460 1735);
FORCEPROP 0 LASTPIN (-2650 1725) $PN 3
J 0
(-2640 1735);
DISPLAY 0.489362 (-2640 1735);
PAINT MONO (-2640 1735);
FORCEPROP 0 LASTPIN (-2650 1975) $PN 4
J 0
(-2640 1985);
DISPLAY 0.489362 (-2640 1985);
PAINT MONO (-2640 1985);
FORCEPROP 2 LAST PART_TYPE SMLF
J 0
(-3125 1600);
DISPLAY 1.021277 (-3125 1600);
FORCEPROP 1 LAST MATERIAL IND
J 0
(-3250 2025);
DISPLAY 0.489362 (-3250 2025);
PAINT SKYBLUE (-3250 2025);
FORCEPROP 2 LAST VALUE 150NH
J 0
(-3150 2025);
DISPLAY 0.489362 (-3150 2025);
PAINT SKYBLUE (-3150 2025);
FORCEPROP 1 LAST NEEDS_NO_SIZE TRUE
J 0
(-3050 1850);
DISPLAY 0.468085 (-3050 1850);
PAINT GREEN (-3050 1850);
DISPLAY INVISIBLE (-3050 1850);
FORCEPROP 2 LAST CDS_LIB pure_quanta
J 0
(-3050 1850);
DISPLAY INVISIBLE (-3050 1850);
FORCEPROP 1 LAST PATH I62
J 0
(-2850 2005);
DISPLAY 0.723404 (-2850 2005);
PAINT GREEN (-2850 2005);
DISPLAY INVISIBLE (-2850 2005);
FORCEPROP 1 LAST PART_NUMBER CV+15^0TZ04
J 0
(-3000 2025);
DISPLAY 0.489362 (-3000 2025);
PAINT SKYBLUE (-3000 2025);
DISPLAY INVISIBLE (-3000 2025);
FORCEADD OFFPAGE..6
R 2
(-2225 1725);
FORCEPROP 2 LAST $XR0 219 
J 0
(-2011 1725);
DISPLAY 0.638298 (-2011 1725);
PAINT MONO (-2011 1725);
FORCEPROP 2 LAST CDS_LIB standard
J 0
(-2225 1725);
DISPLAY INVISIBLE (-2225 1725);
FORCEPROP 1 LAST OFFPAGE TRUE
J 2
(-2550 1600);
DISPLAY 0.872340 (-2550 1600);
PAINT GREEN (-2550 1600);
DISPLAY INVISIBLE (-2550 1600);
FORCEPROP 1 LAST COMMENT_BODY TRUE
J 2
(-2325 1650);
DISPLAY 0.872340 (-2325 1650);
PAINT GREEN (-2325 1650);
DISPLAY INVISIBLE (-2325 1650);
FORCEPROP 2 LAST PATH I63
J 0
(-2000 1775);
DISPLAY 0.680851 (-2000 1775);
DISPLAY INVISIBLE (-2000 1775);
FORCEADD Q_RES..1
(-3775 3575);
FORCEPROP 1 LAST LOCATION PR261
J 0
(-3825 3600);
DISPLAY 0.489362 (-3825 3600);
PAINT SKYBLUE (-3825 3600);
FORCEPROP 0 LAST $SEC 1
J 0
(-3525 3725);
DISPLAY 0.680851 (-3525 3725);
PAINT MONO (-3525 3725);
DISPLAY INVISIBLE (-3525 3725);
FORCEPROP 0 LAST CDS_SEC 1
J 0
(-3525 3725);
DISPLAY 1.021277 (-3525 3725);
DISPLAY INVISIBLE (-3525 3725);
FORCEPROP 1 LASTPIN (-3875 3575) $PN 1
J 0
(-3863 3587);
DISPLAY 0.489362 (-3863 3587);
PAINT MONO (-3863 3587);
FORCEPROP 1 LASTPIN (-3675 3575) $PN 2
J 0
(-3713 3587);
DISPLAY 0.489362 (-3713 3587);
PAINT MONO (-3713 3587);
FORCEPROP 1 LAST VALUE 0
J 2
(-3975 3600);
DISPLAY 0.489362 (-3975 3600);
PAINT SKYBLUE (-3975 3600);
FORCEPROP 1 LAST PACK_TYPE 0402LF
J 0
(-3675 3525);
DISPLAY 0.489362 (-3675 3525);
PAINT SKYBLUE (-3675 3525);
FORCEPROP 1 LAST TOLERANCE 5%
J 0
(-3950 3600);
DISPLAY 0.489362 (-3950 3600);
PAINT SKYBLUE (-3950 3600);
FORCEPROP 1 LAST MATERIAL CHIP
J 0
(-3650 3475);
DISPLAY 0.489362 (-3650 3475);
PAINT SKYBLUE (-3650 3475);
FORCEPROP 1 LAST WATTAGE 1/16W
J 2
(-3550 3625);
DISPLAY 0.489362 (-3550 3625);
PAINT SKYBLUE (-3550 3625);
FORCEPROP 2 LAST CDS_LIB pure_quanta
J 0
(-3775 3575);
DISPLAY INVISIBLE (-3775 3575);
FORCEPROP 1 LAST PATH I64
J 0
(-3825 3725);
DISPLAY 0.978723 (-3825 3725);
PAINT WHITE (-3825 3725);
DISPLAY INVISIBLE (-3825 3725);
FORCEPROP 1 LAST PART_NUMBER CS00002JB13
J 0
(-4075 3525);
DISPLAY 0.489362 (-4075 3525);
PAINT SKYBLUE (-4075 3525);
DISPLAY INVISIBLE (-4075 3525);
FORCEADD Q_CAPP..1
(-2800 2925);
FORCEPROP 1 LAST LOCATION PC106
J 0
(-2750 3025);
DISPLAY 0.489362 (-2750 3025);
PAINT SKYBLUE (-2750 3025);
FORCEPROP 0 LAST $SEC 1
J 0
(-2750 3075);
DISPLAY 0.680851 (-2750 3075);
PAINT MONO (-2750 3075);
DISPLAY INVISIBLE (-2750 3075);
FORCEPROP 0 LAST CDS_SEC 1
J 0
(-2750 3075);
DISPLAY 1.021277 (-2750 3075);
DISPLAY INVISIBLE (-2750 3075);
FORCEPROP 1 LASTPIN (-2800 3025) $PN 1
J 0
(-2790 3010);
DISPLAY 0.489362 (-2790 3010);
PAINT MONO (-2790 3010);
FORCEPROP 1 LASTPIN (-2800 2825) $PN 2
J 0
(-2790 2810);
DISPLAY 0.489362 (-2790 2810);
PAINT MONO (-2790 2810);
FORCEPROP 1 LAST VOLTAGE 4V
J 0
(-2750 2875);
DISPLAY 0.489362 (-2750 2875);
PAINT SKYBLUE (-2750 2875);
FORCEPROP 1 LAST VALUE 220UF
J 0
(-2750 2975);
DISPLAY 0.489362 (-2750 2975);
PAINT SKYBLUE (-2750 2975);
FORCEPROP 1 LAST TOLERANCE 20%
J 0
(-2750 2925);
DISPLAY 0.489362 (-2750 2925);
PAINT SKYBLUE (-2750 2925);
FORCEPROP 1 LAST MATERIAL SPCAP
J 0
(-2750 2825);
DISPLAY 0.489362 (-2750 2825);
PAINT SKYBLUE (-2750 2825);
FORCEPROP 1 LAST PACK_TYPE SMLF
J 0
(-2750 2775);
DISPLAY 0.489362 (-2750 2775);
PAINT SKYBLUE (-2750 2775);
FORCEPROP 2 LAST CDS_LIB pure_quanta
J 0
(-2800 2925);
DISPLAY INVISIBLE (-2800 2925);
FORCEPROP 1 LAST PATH I65
J 0
(-2750 3075);
DISPLAY 0.978723 (-2750 3075);
DISPLAY INVISIBLE (-2750 3075);
FORCEPROP 1 LAST PART_NUMBER CH122KM8801
J 0
(-2750 2725);
DISPLAY 0.489362 (-2750 2725);
PAINT SKYBLUE (-2750 2725);
DISPLAY INVISIBLE (-2750 2725);
FORCEADD Q_CAPP..1
(-2450 2925);
FORCEPROP 1 LAST LOCATION PC387
J 0
(-2400 3025);
DISPLAY 0.489362 (-2400 3025);
PAINT SKYBLUE (-2400 3025);
FORCEPROP 0 LAST $SEC 1
J 0
(-2400 3075);
DISPLAY 0.680851 (-2400 3075);
PAINT MONO (-2400 3075);
DISPLAY INVISIBLE (-2400 3075);
FORCEPROP 0 LAST CDS_SEC 1
J 0
(-2400 3075);
DISPLAY 1.021277 (-2400 3075);
DISPLAY INVISIBLE (-2400 3075);
FORCEPROP 1 LASTPIN (-2450 3025) $PN 1
J 0
(-2440 3010);
DISPLAY 0.489362 (-2440 3010);
PAINT MONO (-2440 3010);
FORCEPROP 1 LASTPIN (-2450 2825) $PN 2
J 0
(-2440 2810);
DISPLAY 0.489362 (-2440 2810);
PAINT MONO (-2440 2810);
FORCEPROP 1 LAST PACK_TYPE SMLF
J 0
(-2400 2775);
DISPLAY 0.489362 (-2400 2775);
PAINT SKYBLUE (-2400 2775);
FORCEPROP 1 LAST VALUE 220UF
J 0
(-2400 2975);
DISPLAY 0.489362 (-2400 2975);
PAINT SKYBLUE (-2400 2975);
FORCEPROP 1 LAST TOLERANCE 20%
J 0
(-2400 2925);
DISPLAY 0.489362 (-2400 2925);
PAINT SKYBLUE (-2400 2925);
FORCEPROP 1 LAST VOLTAGE 4V
J 0
(-2400 2875);
DISPLAY 0.489362 (-2400 2875);
PAINT SKYBLUE (-2400 2875);
FORCEPROP 1 LAST MATERIAL SPCAP
J 0
(-2400 2825);
DISPLAY 0.489362 (-2400 2825);
PAINT SKYBLUE (-2400 2825);
FORCEPROP 2 LAST CDS_LIB pure_quanta
J 0
(-2450 2925);
DISPLAY INVISIBLE (-2450 2925);
FORCEPROP 1 LAST PATH I66
J 0
(-2400 3075);
DISPLAY 0.978723 (-2400 3075);
DISPLAY INVISIBLE (-2400 3075);
FORCEPROP 1 LAST PART_NUMBER CH122KM8801
J 0
(-2400 2725);
DISPLAY 0.489362 (-2400 2725);
PAINT SKYBLUE (-2400 2725);
DISPLAY INVISIBLE (-2400 2725);
FORCEADD Q_CAPP..1
(-2125 2925);
FORCEPROP 1 LAST LOCATION PC388
J 0
(-2075 3025);
DISPLAY 0.489362 (-2075 3025);
PAINT SKYBLUE (-2075 3025);
FORCEPROP 0 LAST $SEC 1
J 0
(-2075 3075);
DISPLAY 0.680851 (-2075 3075);
PAINT MONO (-2075 3075);
DISPLAY INVISIBLE (-2075 3075);
FORCEPROP 0 LAST CDS_SEC 1
J 0
(-2075 3075);
DISPLAY 1.021277 (-2075 3075);
DISPLAY INVISIBLE (-2075 3075);
FORCEPROP 1 LASTPIN (-2125 3025) $PN 1
J 0
(-2115 3010);
DISPLAY 0.489362 (-2115 3010);
PAINT MONO (-2115 3010);
FORCEPROP 1 LASTPIN (-2125 2825) $PN 2
J 0
(-2115 2810);
DISPLAY 0.489362 (-2115 2810);
PAINT MONO (-2115 2810);
FORCEPROP 1 LAST VALUE 220UF
J 0
(-2075 2975);
DISPLAY 0.489362 (-2075 2975);
PAINT SKYBLUE (-2075 2975);
FORCEPROP 1 LAST TOLERANCE 20%
J 0
(-2075 2925);
DISPLAY 0.489362 (-2075 2925);
PAINT SKYBLUE (-2075 2925);
FORCEPROP 1 LAST PACK_TYPE SMLF
J 0
(-2075 2775);
DISPLAY 0.489362 (-2075 2775);
PAINT SKYBLUE (-2075 2775);
FORCEPROP 1 LAST VOLTAGE 4V
J 0
(-2075 2875);
DISPLAY 0.489362 (-2075 2875);
PAINT SKYBLUE (-2075 2875);
FORCEPROP 1 LAST MATERIAL SPCAP
J 0
(-2075 2825);
DISPLAY 0.489362 (-2075 2825);
PAINT SKYBLUE (-2075 2825);
FORCEPROP 2 LAST CDS_LIB pure_quanta
J 0
(-2125 2925);
DISPLAY INVISIBLE (-2125 2925);
FORCEPROP 1 LAST PATH I67
J 0
(-2075 3075);
DISPLAY 0.978723 (-2075 3075);
DISPLAY INVISIBLE (-2075 3075);
FORCEPROP 1 LAST PART_NUMBER CH122KM8801
J 0
(-2075 2725);
DISPLAY 0.489362 (-2075 2725);
PAINT SKYBLUE (-2075 2725);
DISPLAY INVISIBLE (-2075 2725);
FORCEADD Q_CAP..1
(-1650 1775);
FORCEPROP 1 LAST LOCATION PC394_2
J 0
(-1600 1900);
DISPLAY 0.489362 (-1600 1900);
PAINT SKYBLUE (-1600 1900);
FORCEPROP 0 LAST $SEC 1
J 0
(-1600 1950);
DISPLAY 0.680851 (-1600 1950);
PAINT MONO (-1600 1950);
DISPLAY INVISIBLE (-1600 1950);
FORCEPROP 0 LAST CDS_SEC 1
J 0
(-1600 1950);
DISPLAY 1.021277 (-1600 1950);
DISPLAY INVISIBLE (-1600 1950);
FORCEPROP 1 LASTPIN (-1650 1875) $PN 1
J 0
(-1640 1855);
DISPLAY 0.489362 (-1640 1855);
PAINT MONO (-1640 1855);
FORCEPROP 1 LASTPIN (-1650 1675) $PN 2
J 0
(-1640 1655);
DISPLAY 0.489362 (-1640 1655);
PAINT MONO (-1640 1655);
FORCEPROP 1 LAST VOLTAGE 4V
J 0
(-1600 1800);
DISPLAY 0.489362 (-1600 1800);
PAINT SKYBLUE (-1600 1800);
FORCEPROP 1 LAST VALUE 22UF
J 0
(-1600 1850);
DISPLAY 0.489362 (-1600 1850);
PAINT SKYBLUE (-1600 1850);
FORCEPROP 1 LAST TOLERANCE 20%
J 0
(-1600 1750);
DISPLAY 0.489362 (-1600 1750);
PAINT SKYBLUE (-1600 1750);
FORCEPROP 1 LAST MATERIAL X6S
J 0
(-1600 1700);
DISPLAY 0.489362 (-1600 1700);
PAINT SKYBLUE (-1600 1700);
FORCEPROP 1 LAST PACK_TYPE C0805
J 0
(-1600 1650);
DISPLAY 0.489362 (-1600 1650);
PAINT SKYBLUE (-1600 1650);
FORCEPROP 2 LAST CDS_LIB pure_quanta
J 0
(-1650 1775);
DISPLAY INVISIBLE (-1650 1775);
FORCEPROP 1 LAST PATH I68
J 0
(-1600 1925);
DISPLAY 0.978723 (-1600 1925);
PAINT WHITE (-1600 1925);
DISPLAY INVISIBLE (-1600 1925);
FORCEPROP 1 LAST PART_NUMBER CH622KMEA03
J 0
(-1600 1600);
DISPLAY 0.489362 (-1600 1600);
PAINT SKYBLUE (-1600 1600);
DISPLAY INVISIBLE (-1600 1600);
FORCEADD UNIVERSAL_GND..1
(-1225 1450);
FORCEPROP 3 LASTPIN (-1225 1500) SIG_NAME GND\g
J 0
(-1215 1510);
DISPLAY 0.659574 (-1215 1510);
PAINT MONO (-1215 1510);
DISPLAY INVISIBLE (-1215 1510);
FORCEPROP 2 LAST CDS_LIB pure_quanta_power
J 0
(-1225 1450);
PAINT MONO (-1225 1450);
DISPLAY INVISIBLE (-1225 1450);
FORCEPROP 1 LAST HDL_POWER GND
J 1
(-1200 1375);
DISPLAY 0.872340 (-1200 1375);
PAINT GREEN (-1200 1375);
DISPLAY INVISIBLE (-1200 1375);
FORCEPROP 1 LAST PATH I69
J 0
(-1150 1450);
DISPLAY 0.872340 (-1150 1450);
PAINT AQUA (-1150 1450);
DISPLAY INVISIBLE (-1150 1450);
FORCEADD OFFPAGE..1
(-8200 1875);
FORCEPROP 2 LAST $XR5 223 
J 0
(-9052 1875);
DISPLAY 0.638298 (-9052 1875);
PAINT MONO (-9052 1875);
FORCEPROP 2 LAST $XR4 222 
J 0
(-8932 1875);
DISPLAY 0.638298 (-8932 1875);
PAINT MONO (-8932 1875);
FORCEPROP 2 LAST $XR3 220 
J 0
(-8812 1875);
DISPLAY 0.638298 (-8812 1875);
PAINT MONO (-8812 1875);
FORCEPROP 2 LAST $XR2 219 
J 0
(-8692 1875);
DISPLAY 0.638298 (-8692 1875);
PAINT MONO (-8692 1875);
FORCEPROP 2 LAST $XR1 218 
J 0
(-8572 1875);
DISPLAY 0.638298 (-8572 1875);
PAINT MONO (-8572 1875);
FORCEPROP 2 LAST $XR0 217 
J 0
(-8452 1875);
DISPLAY 0.638298 (-8452 1875);
PAINT MONO (-8452 1875);
FORCEPROP 2 LAST CDS_LIB standard
J 0
(-8200 1875);
DISPLAY INVISIBLE (-8200 1875);
FORCEPROP 1 LAST OFFPAGE TRUE
J 0
(-7875 1750);
DISPLAY 0.872340 (-7875 1750);
PAINT GREEN (-7875 1750);
DISPLAY INVISIBLE (-7875 1750);
FORCEPROP 1 LAST COMMENT_BODY TRUE
J 0
(-8075 1775);
DISPLAY 0.872340 (-8075 1775);
PAINT GREEN (-8075 1775);
DISPLAY INVISIBLE (-8075 1775);
FORCEPROP 2 LAST PATH I7
J 0
(-8450 1925);
DISPLAY 0.680851 (-8450 1925);
DISPLAY INVISIBLE (-8450 1925);
FORCEADD Q_CAP..1
(-1225 1775);
FORCEPROP 1 LAST LOCATION PC397_2
J 0
(-1175 1900);
DISPLAY 0.489362 (-1175 1900);
PAINT SKYBLUE (-1175 1900);
FORCEPROP 0 LAST $SEC 1
J 0
(-1175 1950);
DISPLAY 0.680851 (-1175 1950);
PAINT MONO (-1175 1950);
DISPLAY INVISIBLE (-1175 1950);
FORCEPROP 0 LAST CDS_SEC 1
J 0
(-1175 1950);
DISPLAY 1.021277 (-1175 1950);
DISPLAY INVISIBLE (-1175 1950);
FORCEPROP 1 LASTPIN (-1225 1875) $PN 1
J 0
(-1215 1855);
DISPLAY 0.489362 (-1215 1855);
PAINT MONO (-1215 1855);
FORCEPROP 1 LASTPIN (-1225 1675) $PN 2
J 0
(-1215 1655);
DISPLAY 0.489362 (-1215 1655);
PAINT MONO (-1215 1655);
FORCEPROP 1 LAST VOLTAGE 4V
J 0
(-1175 1800);
DISPLAY 0.489362 (-1175 1800);
PAINT SKYBLUE (-1175 1800);
FORCEPROP 1 LAST VALUE 22UF
J 0
(-1175 1850);
DISPLAY 0.489362 (-1175 1850);
PAINT SKYBLUE (-1175 1850);
FORCEPROP 1 LAST TOLERANCE 20%
J 0
(-1175 1750);
DISPLAY 0.489362 (-1175 1750);
PAINT SKYBLUE (-1175 1750);
FORCEPROP 1 LAST MATERIAL X6S
J 0
(-1175 1700);
DISPLAY 0.489362 (-1175 1700);
PAINT SKYBLUE (-1175 1700);
FORCEPROP 1 LAST PACK_TYPE C0805
J 0
(-1175 1650);
DISPLAY 0.489362 (-1175 1650);
PAINT SKYBLUE (-1175 1650);
FORCEPROP 2 LAST CDS_LIB pure_quanta
J 0
(-1225 1775);
DISPLAY INVISIBLE (-1225 1775);
FORCEPROP 1 LAST PATH I70
J 0
(-1175 1925);
DISPLAY 0.978723 (-1175 1925);
PAINT WHITE (-1175 1925);
DISPLAY INVISIBLE (-1175 1925);
FORCEPROP 1 LAST PART_NUMBER CH622KMEA03
J 0
(-1175 1600);
DISPLAY 0.489362 (-1175 1600);
PAINT SKYBLUE (-1175 1600);
DISPLAY INVISIBLE (-1175 1600);
FORCEADD VCC_CORE..1
(-1225 2075);
FORCEPROP 3 LASTPIN (-1225 2025) SIG_NAME PVDDCR_CPU1_P1\g
J 0
(-1215 2035);
DISPLAY 0.659574 (-1215 2035);
PAINT MONO (-1215 2035);
DISPLAY INVISIBLE (-1215 2035);
FORCEPROP 1 LAST HDL_POWER PVDDCR_CPU1_P1
J 1
(-1225 2125);
DISPLAY 0.489362 (-1225 2125);
PAINT GREEN (-1225 2125);
FORCEPROP 2 LAST CDS_LIB pure_quanta_power
J 0
(-1225 2075);
DISPLAY INVISIBLE (-1225 2075);
FORCEPROP 1 LAST PATH I71
J 0
(-1175 2100);
DISPLAY 0.872340 (-1175 2100);
PAINT AQUA (-1175 2100);
DISPLAY INVISIBLE (-1175 2100);
FORCEADD UNIVERSAL_GND..1
(-1500 2550);
FORCEPROP 3 LASTPIN (-1500 2600) SIG_NAME GND\g
J 0
(-1490 2610);
DISPLAY 0.659574 (-1490 2610);
PAINT MONO (-1490 2610);
DISPLAY INVISIBLE (-1490 2610);
FORCEPROP 2 LAST CDS_LIB pure_quanta_power
J 0
(-1500 2550);
DISPLAY INVISIBLE (-1500 2550);
FORCEPROP 1 LAST HDL_POWER GND
J 1
(-1475 2475);
DISPLAY 0.872340 (-1475 2475);
PAINT GREEN (-1475 2475);
DISPLAY INVISIBLE (-1475 2475);
FORCEPROP 1 LAST PATH I72
J 0
(-1425 2550);
DISPLAY 0.872340 (-1425 2550);
PAINT AQUA (-1425 2550);
DISPLAY INVISIBLE (-1425 2550);
FORCEADD Q_CAPP..1
(-1800 2925);
FORCEPROP 1 LAST LOCATION PC389
J 0
(-1750 3025);
DISPLAY 0.489362 (-1750 3025);
PAINT SKYBLUE (-1750 3025);
FORCEPROP 0 LAST $SEC 1
J 0
(-1750 3075);
DISPLAY 0.680851 (-1750 3075);
PAINT MONO (-1750 3075);
DISPLAY INVISIBLE (-1750 3075);
FORCEPROP 0 LAST CDS_SEC 1
J 0
(-1750 3075);
DISPLAY 1.021277 (-1750 3075);
DISPLAY INVISIBLE (-1750 3075);
FORCEPROP 1 LASTPIN (-1800 3025) $PN 1
J 0
(-1790 3010);
DISPLAY 0.489362 (-1790 3010);
PAINT MONO (-1790 3010);
FORCEPROP 1 LASTPIN (-1800 2825) $PN 2
J 0
(-1790 2810);
DISPLAY 0.489362 (-1790 2810);
PAINT MONO (-1790 2810);
FORCEPROP 1 LAST PACK_TYPE SMLF
J 0
(-1750 2775);
DISPLAY 0.489362 (-1750 2775);
PAINT SKYBLUE (-1750 2775);
FORCEPROP 1 LAST VALUE 220UF
J 0
(-1750 2975);
DISPLAY 0.489362 (-1750 2975);
PAINT SKYBLUE (-1750 2975);
FORCEPROP 1 LAST TOLERANCE 20%
J 0
(-1750 2925);
DISPLAY 0.489362 (-1750 2925);
PAINT SKYBLUE (-1750 2925);
FORCEPROP 1 LAST MATERIAL SPCAP
J 0
(-1750 2825);
DISPLAY 0.489362 (-1750 2825);
PAINT SKYBLUE (-1750 2825);
FORCEPROP 1 LAST VOLTAGE 4V
J 0
(-1750 2875);
DISPLAY 0.489362 (-1750 2875);
PAINT SKYBLUE (-1750 2875);
FORCEPROP 2 LAST CDS_LIB pure_quanta
J 0
(-1800 2925);
DISPLAY INVISIBLE (-1800 2925);
FORCEPROP 1 LAST PATH I73
J 0
(-1750 3075);
DISPLAY 0.978723 (-1750 3075);
DISPLAY INVISIBLE (-1750 3075);
FORCEPROP 1 LAST PART_NUMBER CH122KM8801
J 0
(-1750 2725);
DISPLAY 0.489362 (-1750 2725);
PAINT SKYBLUE (-1750 2725);
DISPLAY INVISIBLE (-1750 2725);
FORCEADD Q_CAPP..1
(-1500 2925);
FORCEPROP 1 LAST LOCATION PC391
J 0
(-1450 3025);
DISPLAY 0.489362 (-1450 3025);
PAINT SKYBLUE (-1450 3025);
FORCEPROP 0 LAST $SEC 1
J 0
(-1450 3075);
DISPLAY 0.680851 (-1450 3075);
PAINT MONO (-1450 3075);
DISPLAY INVISIBLE (-1450 3075);
FORCEPROP 0 LAST CDS_SEC 1
J 0
(-1450 3075);
DISPLAY 1.021277 (-1450 3075);
DISPLAY INVISIBLE (-1450 3075);
FORCEPROP 1 LASTPIN (-1500 3025) $PN 1
J 0
(-1490 3010);
DISPLAY 0.489362 (-1490 3010);
PAINT MONO (-1490 3010);
FORCEPROP 1 LASTPIN (-1500 2825) $PN 2
J 0
(-1490 2810);
DISPLAY 0.489362 (-1490 2810);
PAINT MONO (-1490 2810);
FORCEPROP 1 LAST MATERIAL SPCAP
J 0
(-1450 2825);
DISPLAY 0.489362 (-1450 2825);
PAINT SKYBLUE (-1450 2825);
FORCEPROP 1 LAST VALUE 220UF
J 0
(-1450 2975);
DISPLAY 0.489362 (-1450 2975);
PAINT SKYBLUE (-1450 2975);
FORCEPROP 1 LAST TOLERANCE 20%
J 0
(-1450 2925);
DISPLAY 0.489362 (-1450 2925);
PAINT SKYBLUE (-1450 2925);
FORCEPROP 1 LAST VOLTAGE 4V
J 0
(-1450 2875);
DISPLAY 0.489362 (-1450 2875);
PAINT SKYBLUE (-1450 2875);
FORCEPROP 1 LAST PACK_TYPE SMLF
J 0
(-1450 2775);
DISPLAY 0.489362 (-1450 2775);
PAINT SKYBLUE (-1450 2775);
FORCEPROP 2 LAST CDS_LIB pure_quanta
J 0
(-1500 2925);
DISPLAY INVISIBLE (-1500 2925);
FORCEPROP 1 LAST PATH I74
J 0
(-1450 3075);
DISPLAY 0.978723 (-1450 3075);
DISPLAY INVISIBLE (-1450 3075);
FORCEPROP 1 LAST PART_NUMBER CH122KM8801
J 0
(-1450 2725);
DISPLAY 0.489362 (-1450 2725);
PAINT SKYBLUE (-1450 2725);
DISPLAY INVISIBLE (-1450 2725);
FORCEADD VCC_CORE..1
(-1500 3225);
FORCEPROP 3 LASTPIN (-1500 3175) SIG_NAME PVDDCR_CPU1_P1\g
J 0
(-1490 3185);
DISPLAY 0.659574 (-1490 3185);
PAINT MONO (-1490 3185);
DISPLAY INVISIBLE (-1490 3185);
FORCEPROP 1 LAST HDL_POWER PVDDCR_CPU1_P1
J 1
(-1500 3275);
DISPLAY 0.489362 (-1500 3275);
PAINT GREEN (-1500 3275);
FORCEPROP 2 LAST CDS_LIB pure_quanta_power
J 0
(-1500 3225);
DISPLAY INVISIBLE (-1500 3225);
FORCEPROP 1 LAST PATH I75
J 0
(-1450 3250);
DISPLAY 0.872340 (-1450 3250);
PAINT AQUA (-1450 3250);
DISPLAY INVISIBLE (-1450 3250);
FORCEADD UNIVERSAL_GND..1
(-900 4025);
FORCEPROP 3 LASTPIN (-900 4075) SIG_NAME GND\g
J 0
(-890 4085);
DISPLAY 0.659574 (-890 4085);
PAINT MONO (-890 4085);
DISPLAY INVISIBLE (-890 4085);
FORCEPROP 2 LAST CDS_LIB pure_quanta_power
J 0
(-900 4025);
PAINT MONO (-900 4025);
DISPLAY INVISIBLE (-900 4025);
FORCEPROP 1 LAST HDL_POWER GND
J 1
(-875 3950);
DISPLAY 0.872340 (-875 3950);
PAINT GREEN (-875 3950);
DISPLAY INVISIBLE (-875 3950);
FORCEPROP 1 LAST PATH I76
J 0
(-825 4025);
DISPLAY 0.872340 (-825 4025);
PAINT AQUA (-825 4025);
DISPLAY INVISIBLE (-825 4025);
FORCEADD Q_INDUCTOR4P_14..1
(-3450 4475);
FORCEPROP 1 LAST LOCATION PL40
J 0
(-3675 4730);
DISPLAY 0.489362 (-3675 4730);
PAINT SKYBLUE (-3675 4730);
FORCEPROP 0 LAST $SEC 1
J 0
(-3675 4775);
DISPLAY 0.680851 (-3675 4775);
PAINT MONO (-3675 4775);
DISPLAY INVISIBLE (-3675 4775);
FORCEPROP 0 LAST CDS_SEC 1
J 0
(-3675 4775);
DISPLAY 1.021277 (-3675 4775);
DISPLAY INVISIBLE (-3675 4775);
FORCEPROP 0 LASTPIN (-3850 4600) $PN 1
J 2
(-3860 4610);
DISPLAY 0.489362 (-3860 4610);
PAINT MONO (-3860 4610);
FORCEPROP 0 LASTPIN (-3850 4350) $PN 2
J 2
(-3860 4360);
DISPLAY 0.489362 (-3860 4360);
PAINT MONO (-3860 4360);
FORCEPROP 0 LASTPIN (-3050 4350) $PN 3
J 0
(-3040 4360);
DISPLAY 0.489362 (-3040 4360);
PAINT MONO (-3040 4360);
FORCEPROP 0 LASTPIN (-3050 4600) $PN 4
J 0
(-3040 4610);
DISPLAY 0.489362 (-3040 4610);
PAINT MONO (-3040 4610);
FORCEPROP 2 LAST PART_TYPE SMLF
J 0
(-3525 4225);
DISPLAY 1.021277 (-3525 4225);
FORCEPROP 1 LAST MATERIAL IND
J 0
(-3650 4650);
DISPLAY 0.489362 (-3650 4650);
PAINT SKYBLUE (-3650 4650);
FORCEPROP 2 LAST VALUE 150NH
J 0
(-3550 4650);
DISPLAY 0.489362 (-3550 4650);
PAINT SKYBLUE (-3550 4650);
FORCEPROP 2 LAST CDS_LIB pure_quanta
J 0
(-3450 4475);
DISPLAY INVISIBLE (-3450 4475);
FORCEPROP 1 LAST NEEDS_NO_SIZE TRUE
J 0
(-3450 4475);
DISPLAY 0.468085 (-3450 4475);
PAINT GREEN (-3450 4475);
DISPLAY INVISIBLE (-3450 4475);
FORCEPROP 1 LAST PATH I77
J 0
(-3250 4630);
DISPLAY 0.723404 (-3250 4630);
PAINT GREEN (-3250 4630);
DISPLAY INVISIBLE (-3250 4630);
FORCEPROP 1 LAST PART_NUMBER CV+15^0TZ04
J 0
(-3400 4650);
DISPLAY 0.489362 (-3400 4650);
PAINT SKYBLUE (-3400 4650);
DISPLAY INVISIBLE (-3400 4650);
FORCEADD Q_INDUCTOR..1
(-3350 5775);
FORCEPROP 1 LAST LOCATION PL42
J 0
(-3475 5925);
DISPLAY 0.489362 (-3475 5925);
PAINT SKYBLUE (-3475 5925);
FORCEPROP 2 LAST $SEC 1
J 0
(-3475 6050);
DISPLAY 0.680851 (-3475 6050);
PAINT MONO (-3475 6050);
DISPLAY INVISIBLE (-3475 6050);
FORCEPROP 0 LAST CDS_SEC 1
J 0
(-3375 5875);
DISPLAY 1.021277 (-3375 5875);
DISPLAY INVISIBLE (-3375 5875);
FORCEPROP 2 LASTPIN (-3450 5750) $PN 1
J 2
(-3460 5760);
DISPLAY 0.489362 (-3460 5760);
FORCEPROP 2 LASTPIN (-3250 5750) $PN 2
J 0
(-3240 5760);
DISPLAY 0.489362 (-3240 5760);
FORCEPROP 2 LAST PACK_TYPE SMLF
J 0
(-3475 6025);
DISPLAY 0.489362 (-3475 6025);
PAINT SKYBLUE (-3475 6025);
FORCEPROP 2 LAST VALUE 50NH/86A
J 0
(-3475 5975);
DISPLAY 0.489362 (-3475 5975);
PAINT SKYBLUE (-3475 5975);
FORCEPROP 1 LAST MATERIAL IND
J 0
(-3475 5830);
DISPLAY 0.489362 (-3475 5830);
PAINT SKYBLUE (-3475 5830);
FORCEPROP 1 LAST NEEDS_NO_SIZE TRUE
J 0
(-3350 5775);
DISPLAY 0.468085 (-3350 5775);
PAINT GREEN (-3350 5775);
DISPLAY INVISIBLE (-3350 5775);
FORCEPROP 2 LAST CDS_LIB pure_quanta
J 0
(-3350 5775);
PAINT MONO (-3350 5775);
DISPLAY INVISIBLE (-3350 5775);
FORCEPROP 1 LAST PATH I79
J 0
(-3275 5830);
DISPLAY 0.723404 (-3275 5830);
PAINT GREEN (-3275 5830);
DISPLAY INVISIBLE (-3275 5830);
FORCEPROP 1 LAST PART_NUMBER CVA50^0MZ09
J 0
(-3475 5885);
DISPLAY 0.489362 (-3475 5885);
PAINT SKYBLUE (-3475 5885);
DISPLAY INVISIBLE (-3475 5885);
FORCEADD OFFPAGE..5
(-8200 1975);
FORCEPROP 2 LAST $XR0 217 
J 0
(-8455 1975);
DISPLAY 0.638298 (-8455 1975);
PAINT MONO (-8455 1975);
FORCEPROP 2 LAST CDS_LIB standard
J 0
(-8200 1975);
DISPLAY INVISIBLE (-8200 1975);
FORCEPROP 1 LAST OFFPAGE TRUE
J 0
(-7875 1850);
DISPLAY 0.872340 (-7875 1850);
PAINT GREEN (-7875 1850);
DISPLAY INVISIBLE (-7875 1850);
FORCEPROP 1 LAST COMMENT_BODY TRUE
J 0
(-8100 1900);
DISPLAY 0.872340 (-8100 1900);
PAINT GREEN (-8100 1900);
DISPLAY INVISIBLE (-8100 1900);
FORCEPROP 2 LAST PATH I8
J 0
(-8450 2025);
DISPLAY 0.680851 (-8450 2025);
DISPLAY INVISIBLE (-8450 2025);
FORCEADD OFFPAGE..6
R 2
(-2525 4350);
FORCEPROP 2 LAST $XR0 218 
J 0
(-2311 4350);
DISPLAY 0.638298 (-2311 4350);
PAINT MONO (-2311 4350);
FORCEPROP 2 LAST CDS_LIB standard
J 2
(-2525 4350);
DISPLAY INVISIBLE (-2525 4350);
FORCEPROP 1 LAST OFFPAGE TRUE
J 2
(-2850 4225);
DISPLAY 0.872340 (-2850 4225);
PAINT GREEN (-2850 4225);
DISPLAY INVISIBLE (-2850 4225);
FORCEPROP 1 LAST COMMENT_BODY TRUE
J 2
(-2625 4275);
DISPLAY 0.872340 (-2625 4275);
PAINT GREEN (-2625 4275);
DISPLAY INVISIBLE (-2625 4275);
FORCEPROP 2 LAST PATH I80
J 0
(-2300 4400);
DISPLAY 0.680851 (-2300 4400);
DISPLAY INVISIBLE (-2300 4400);
FORCEADD UNIVERSAL_GND..1
(-2875 5175);
FORCEPROP 3 LASTPIN (-2875 5225) SIG_NAME GND\g
J 0
(-2865 5235);
DISPLAY 0.659574 (-2865 5235);
PAINT MONO (-2865 5235);
DISPLAY INVISIBLE (-2865 5235);
FORCEPROP 2 LAST CDS_LIB pure_quanta_power
J 0
(-2875 5175);
DISPLAY INVISIBLE (-2875 5175);
FORCEPROP 1 LAST HDL_POWER GND
J 1
(-2850 5100);
DISPLAY 0.872340 (-2850 5100);
PAINT GREEN (-2850 5100);
DISPLAY INVISIBLE (-2850 5100);
FORCEPROP 1 LAST PATH I81
J 0
(-2800 5175);
DISPLAY 0.872340 (-2800 5175);
PAINT AQUA (-2800 5175);
DISPLAY INVISIBLE (-2800 5175);
FORCEADD Q_CAP..1
(-2025 4400);
FORCEPROP 1 LAST LOCATION PC392
J 0
(-1975 4525);
DISPLAY 0.489362 (-1975 4525);
PAINT SKYBLUE (-1975 4525);
FORCEPROP 0 LAST $SEC 1
J 0
(-1975 4575);
DISPLAY 0.680851 (-1975 4575);
PAINT MONO (-1975 4575);
DISPLAY INVISIBLE (-1975 4575);
FORCEPROP 0 LAST CDS_SEC 1
J 0
(-1975 4575);
DISPLAY 1.021277 (-1975 4575);
DISPLAY INVISIBLE (-1975 4575);
FORCEPROP 1 LASTPIN (-2025 4500) $PN 1
J 0
(-2015 4480);
DISPLAY 0.489362 (-2015 4480);
PAINT MONO (-2015 4480);
FORCEPROP 1 LASTPIN (-2025 4300) $PN 2
J 0
(-2015 4280);
DISPLAY 0.489362 (-2015 4280);
PAINT MONO (-2015 4280);
FORCEPROP 1 LAST MATERIAL X7R
J 0
(-1975 4325);
DISPLAY 0.489362 (-1975 4325);
PAINT SKYBLUE (-1975 4325);
FORCEPROP 1 LAST TOLERANCE 10%
J 0
(-1975 4375);
DISPLAY 0.489362 (-1975 4375);
PAINT SKYBLUE (-1975 4375);
FORCEPROP 1 LAST VALUE 0.1UF
J 0
(-1975 4475);
DISPLAY 0.489362 (-1975 4475);
PAINT SKYBLUE (-1975 4475);
FORCEPROP 1 LAST VOLTAGE 25V
J 0
(-1975 4425);
DISPLAY 0.489362 (-1975 4425);
PAINT SKYBLUE (-1975 4425);
FORCEPROP 1 LAST PACK_TYPE 0402
J 0
(-1975 4275);
DISPLAY 0.489362 (-1975 4275);
PAINT SKYBLUE (-1975 4275);
FORCEPROP 2 LAST CDS_LIB pure_quanta
J 0
(-2025 4400);
DISPLAY INVISIBLE (-2025 4400);
FORCEPROP 1 LAST PATH I82
J 0
(-1975 4550);
DISPLAY 0.978723 (-1975 4550);
PAINT WHITE (-1975 4550);
DISPLAY INVISIBLE (-1975 4550);
FORCEPROP 1 LAST PART_NUMBER CH4104K1B00
J 0
(-1975 4225);
DISPLAY 0.489362 (-1975 4225);
PAINT SKYBLUE (-1975 4225);
DISPLAY INVISIBLE (-1975 4225);
FORCEADD Q_CAP..1
(-2875 5550);
FORCEPROP 1 LAST LOCATION PC375
J 0
(-2825 5700);
DISPLAY 0.489362 (-2825 5700);
PAINT SKYBLUE (-2825 5700);
FORCEPROP 0 LAST $SEC 1
J 0
(-2825 5725);
DISPLAY 0.680851 (-2825 5725);
PAINT MONO (-2825 5725);
DISPLAY INVISIBLE (-2825 5725);
FORCEPROP 0 LAST CDS_SEC 1
J 0
(-2825 5725);
DISPLAY 0.680851 (-2825 5725);
DISPLAY INVISIBLE (-2825 5725);
FORCEPROP 1 LASTPIN (-2875 5650) $PN 1
J 0
(-2865 5630);
DISPLAY 0.787234 (-2865 5630);
PAINT MONO (-2865 5630);
FORCEPROP 1 LASTPIN (-2875 5450) $PN 2
J 0
(-2865 5430);
DISPLAY 0.787234 (-2865 5430);
PAINT MONO (-2865 5430);
FORCEPROP 1 LAST VALUE 0.1UF
J 0
(-2825 5650);
DISPLAY 0.489362 (-2825 5650);
PAINT SKYBLUE (-2825 5650);
FORCEPROP 1 LAST TOLERANCE 10%
J 0
(-2825 5550);
DISPLAY 0.489362 (-2825 5550);
PAINT SKYBLUE (-2825 5550);
FORCEPROP 1 LAST MATERIAL X7R
J 0
(-2825 5500);
DISPLAY 0.489362 (-2825 5500);
PAINT SKYBLUE (-2825 5500);
FORCEPROP 1 LAST PACK_TYPE 0402
J 0
(-2825 5450);
DISPLAY 0.489362 (-2825 5450);
PAINT SKYBLUE (-2825 5450);
FORCEPROP 1 LAST VOLTAGE 25V
J 0
(-2825 5600);
DISPLAY 0.489362 (-2825 5600);
PAINT SKYBLUE (-2825 5600);
FORCEPROP 2 LAST CDS_LIB pure_quanta
J 0
(-2875 5550);
DISPLAY INVISIBLE (-2875 5550);
FORCEPROP 1 LAST PATH I83
J 0
(-2825 5700);
DISPLAY 0.978723 (-2825 5700);
PAINT WHITE (-2825 5700);
DISPLAY INVISIBLE (-2825 5700);
FORCEPROP 1 LAST PART_NUMBER CH4104K1B00
J 0
(-2825 5400);
DISPLAY 0.489362 (-2825 5400);
PAINT SKYBLUE (-2825 5400);
DISPLAY INVISIBLE (-2825 5400);
FORCEADD VCC_CORE..1
(-2875 5875);
FORCEPROP 3 LASTPIN (-2875 5825) SIG_NAME P12V_AUX\g
J 0
(-2865 5835);
DISPLAY 0.659574 (-2865 5835);
PAINT MONO (-2865 5835);
DISPLAY INVISIBLE (-2865 5835);
FORCEPROP 1 LAST HDL_POWER P12V_AUX
J 1
(-2875 5925);
DISPLAY 0.489362 (-2875 5925);
PAINT GREEN (-2875 5925);
FORCEPROP 2 LAST CDS_LIB pure_quanta_power
J 0
(-2875 5875);
DISPLAY INVISIBLE (-2875 5875);
FORCEPROP 1 LAST PATH I84
J 0
(-2825 5900);
DISPLAY 0.872340 (-2825 5900);
PAINT AQUA (-2825 5900);
DISPLAY INVISIBLE (-2825 5900);
FORCEADD Q_CAP..1
(-1675 4400);
FORCEPROP 1 LAST LOCATION PC395_1
J 0
(-1625 4525);
DISPLAY 0.489362 (-1625 4525);
PAINT SKYBLUE (-1625 4525);
FORCEPROP 0 LAST $SEC 1
J 0
(-1625 4575);
DISPLAY 0.680851 (-1625 4575);
PAINT MONO (-1625 4575);
DISPLAY INVISIBLE (-1625 4575);
FORCEPROP 0 LAST CDS_SEC 1
J 0
(-1625 4575);
DISPLAY 1.021277 (-1625 4575);
DISPLAY INVISIBLE (-1625 4575);
FORCEPROP 1 LASTPIN (-1675 4500) $PN 1
J 0
(-1665 4480);
DISPLAY 0.489362 (-1665 4480);
PAINT MONO (-1665 4480);
FORCEPROP 1 LASTPIN (-1675 4300) $PN 2
J 0
(-1665 4280);
DISPLAY 0.489362 (-1665 4280);
PAINT MONO (-1665 4280);
FORCEPROP 1 LAST VOLTAGE 4V
J 0
(-1625 4425);
DISPLAY 0.489362 (-1625 4425);
PAINT SKYBLUE (-1625 4425);
FORCEPROP 1 LAST VALUE 22UF
J 0
(-1625 4475);
DISPLAY 0.489362 (-1625 4475);
PAINT SKYBLUE (-1625 4475);
FORCEPROP 1 LAST MATERIAL X6S
J 0
(-1625 4325);
DISPLAY 0.489362 (-1625 4325);
PAINT SKYBLUE (-1625 4325);
FORCEPROP 1 LAST PACK_TYPE C0805
J 0
(-1625 4275);
DISPLAY 0.489362 (-1625 4275);
PAINT SKYBLUE (-1625 4275);
FORCEPROP 1 LAST TOLERANCE 20%
J 0
(-1625 4375);
DISPLAY 0.489362 (-1625 4375);
PAINT SKYBLUE (-1625 4375);
FORCEPROP 2 LAST CDS_LIB pure_quanta
J 0
(-1675 4400);
DISPLAY INVISIBLE (-1675 4400);
FORCEPROP 1 LAST PATH I85
J 0
(-1625 4550);
DISPLAY 0.978723 (-1625 4550);
PAINT WHITE (-1625 4550);
DISPLAY INVISIBLE (-1625 4550);
FORCEPROP 1 LAST PART_NUMBER CH622KMEA03
J 0
(-1625 4225);
DISPLAY 0.489362 (-1625 4225);
PAINT SKYBLUE (-1625 4225);
DISPLAY INVISIBLE (-1625 4225);
FORCEADD Q_CAP..1
(-1250 4400);
FORCEPROP 1 LAST LOCATION PC398_1
J 0
(-1200 4525);
DISPLAY 0.489362 (-1200 4525);
PAINT SKYBLUE (-1200 4525);
FORCEPROP 0 LAST $SEC 1
J 0
(-1200 4575);
DISPLAY 0.680851 (-1200 4575);
PAINT MONO (-1200 4575);
DISPLAY INVISIBLE (-1200 4575);
FORCEPROP 0 LAST CDS_SEC 1
J 0
(-1200 4575);
DISPLAY 1.021277 (-1200 4575);
DISPLAY INVISIBLE (-1200 4575);
FORCEPROP 1 LASTPIN (-1250 4500) $PN 1
J 0
(-1240 4480);
DISPLAY 0.489362 (-1240 4480);
PAINT MONO (-1240 4480);
FORCEPROP 1 LASTPIN (-1250 4300) $PN 2
J 0
(-1240 4280);
DISPLAY 0.489362 (-1240 4280);
PAINT MONO (-1240 4280);
FORCEPROP 1 LAST VOLTAGE 4V
J 0
(-1200 4425);
DISPLAY 0.489362 (-1200 4425);
PAINT SKYBLUE (-1200 4425);
FORCEPROP 1 LAST VALUE 22UF
J 0
(-1200 4475);
DISPLAY 0.489362 (-1200 4475);
PAINT SKYBLUE (-1200 4475);
FORCEPROP 1 LAST TOLERANCE 20%
J 0
(-1200 4375);
DISPLAY 0.489362 (-1200 4375);
PAINT SKYBLUE (-1200 4375);
FORCEPROP 1 LAST MATERIAL X6S
J 0
(-1200 4325);
DISPLAY 0.489362 (-1200 4325);
PAINT SKYBLUE (-1200 4325);
FORCEPROP 1 LAST PACK_TYPE C0805
J 0
(-1200 4275);
DISPLAY 0.489362 (-1200 4275);
PAINT SKYBLUE (-1200 4275);
FORCEPROP 2 LAST CDS_LIB pure_quanta
J 0
(-1250 4400);
DISPLAY INVISIBLE (-1250 4400);
FORCEPROP 1 LAST PATH I86
J 0
(-1200 4550);
DISPLAY 0.978723 (-1200 4550);
PAINT WHITE (-1200 4550);
DISPLAY INVISIBLE (-1200 4550);
FORCEPROP 1 LAST PART_NUMBER CH622KMEA03
J 0
(-1200 4225);
DISPLAY 0.489362 (-1200 4225);
PAINT SKYBLUE (-1200 4225);
DISPLAY INVISIBLE (-1200 4225);
FORCEADD Q_RES..2
(-900 4400);
FORCEPROP 1 LAST LOCATION PR342
J 0
(-855 4525);
DISPLAY 0.489362 (-855 4525);
PAINT SKYBLUE (-855 4525);
FORCEPROP 0 LAST $SEC 1
J 0
(-850 4550);
DISPLAY 0.680851 (-850 4550);
PAINT MONO (-850 4550);
DISPLAY INVISIBLE (-850 4550);
FORCEPROP 0 LAST CDS_SEC 1
J 0
(-850 4550);
DISPLAY 1.021277 (-850 4550);
DISPLAY INVISIBLE (-850 4550);
FORCEPROP 1 LASTPIN (-900 4500) $PN 1
J 0
(-895 4462);
DISPLAY 0.787234 (-895 4462);
PAINT MONO (-895 4462);
DISPLAY INVISIBLE (-895 4462);
FORCEPROP 1 LASTPIN (-900 4300) $PN 2
J 0
(-895 4310);
DISPLAY 0.787234 (-895 4310);
PAINT MONO (-895 4310);
DISPLAY INVISIBLE (-895 4310);
FORCEPROP 1 LAST PACK_TYPE 0402LF
J 0
(-860 4225);
DISPLAY 0.489362 (-860 4225);
PAINT SKYBLUE (-860 4225);
FORCEPROP 1 LAST VALUE 1K
J 0
(-855 4475);
DISPLAY 0.489362 (-855 4475);
PAINT SKYBLUE (-855 4475);
FORCEPROP 1 LAST TOLERANCE 1%
J 0
(-855 4425);
DISPLAY 0.489362 (-855 4425);
PAINT SKYBLUE (-855 4425);
FORCEPROP 1 LAST MATERIAL CHIP
J 0
(-860 4325);
DISPLAY 0.489362 (-860 4325);
PAINT SKYBLUE (-860 4325);
FORCEPROP 1 LAST WATTAGE 1/16W
J 0
(-860 4375);
DISPLAY 0.489362 (-860 4375);
PAINT SKYBLUE (-860 4375);
FORCEPROP 2 LAST CDS_LIB pure_quanta
J 0
(-900 4400);
DISPLAY INVISIBLE (-900 4400);
FORCEPROP 1 LAST PATH I87
J 0
(-850 4575);
DISPLAY 0.978723 (-850 4575);
PAINT WHITE (-850 4575);
DISPLAY INVISIBLE (-850 4575);
FORCEPROP 1 LAST PART_NUMBER CS21002FB06
J 0
(-860 4275);
DISPLAY 0.489362 (-860 4275);
PAINT SKYBLUE (-860 4275);
DISPLAY INVISIBLE (-860 4275);
FORCEADD VCC_CORE..1
(-900 4750);
FORCEPROP 3 LASTPIN (-900 4700) SIG_NAME PVDDCR_CPU1_P1\g
J 0
(-890 4710);
DISPLAY 0.659574 (-890 4710);
PAINT MONO (-890 4710);
DISPLAY INVISIBLE (-890 4710);
FORCEPROP 1 LAST HDL_POWER PVDDCR_CPU1_P1
J 1
(-900 4800);
DISPLAY 0.489362 (-900 4800);
PAINT GREEN (-900 4800);
FORCEPROP 2 LAST CDS_LIB pure_quanta_power
J 0
(-900 4750);
DISPLAY INVISIBLE (-900 4750);
FORCEPROP 1 LAST PATH I88
J 0
(-850 4775);
DISPLAY 0.872340 (-850 4775);
PAINT AQUA (-850 4775);
DISPLAY INVISIBLE (-850 4775);
FORCEADD Q_RES..1
R 1
(-9225 6000);
FORCEPROP 1 LAST LOCATION PR340
J 0
(-9200 6150);
DISPLAY 0.489362 (-9200 6150);
PAINT SKYBLUE (-9200 6150);
FORCEPROP 0 LAST $SEC 1
R 1
J 0
(-9200 6175);
DISPLAY 0.680851 (-9200 6175);
PAINT MONO (-9200 6175);
DISPLAY INVISIBLE (-9200 6175);
FORCEPROP 0 LAST CDS_SEC 1
R 1
J 0
(-9200 6175);
DISPLAY 1.021277 (-9200 6175);
DISPLAY INVISIBLE (-9200 6175);
FORCEPROP 1 LASTPIN (-9225 5900) $PN 1
R 1
J 0
(-9237 5912);
DISPLAY 0.787234 (-9237 5912);
PAINT MONO (-9237 5912);
DISPLAY INVISIBLE (-9237 5912);
FORCEPROP 1 LASTPIN (-9225 6100) $PN 2
R 1
J 0
(-9237 6062);
DISPLAY 0.787234 (-9237 6062);
PAINT MONO (-9237 6062);
DISPLAY INVISIBLE (-9237 6062);
FORCEPROP 1 LAST VALUE 0
J 2
(-9175 6100);
DISPLAY 0.489362 (-9175 6100);
PAINT SKYBLUE (-9175 6100);
FORCEPROP 1 LAST PACK_TYPE 0402LF
J 0
(-9200 5850);
DISPLAY 0.489362 (-9200 5850);
PAINT SKYBLUE (-9200 5850);
FORCEPROP 1 LAST TOLERANCE 5%
J 0
(-9200 6050);
DISPLAY 0.489362 (-9200 6050);
PAINT SKYBLUE (-9200 6050);
FORCEPROP 1 LAST MATERIAL CHIP
J 0
(-9200 5950);
DISPLAY 0.489362 (-9200 5950);
PAINT SKYBLUE (-9200 5950);
FORCEPROP 1 LAST WATTAGE 1/16W
J 0
(-9200 6000);
DISPLAY 0.489362 (-9200 6000);
PAINT SKYBLUE (-9200 6000);
FORCEPROP 2 LAST CDS_LIB pure_quanta
J 0
(-9225 6000);
DISPLAY INVISIBLE (-9225 6000);
FORCEPROP 1 LAST PATH I89
R 1
J 0
(-9375 5950);
DISPLAY 0.978723 (-9375 5950);
PAINT WHITE (-9375 5950);
DISPLAY INVISIBLE (-9375 5950);
FORCEPROP 1 LAST PART_NUMBER CS00002JB13
J 0
(-9200 5900);
DISPLAY 0.489362 (-9200 5900);
PAINT SKYBLUE (-9200 5900);
DISPLAY INVISIBLE (-9200 5900);
FORCEADD UNIVERSAL_GND..1
(-8475 2200);
FORCEPROP 3 LASTPIN (-8475 2250) SIG_NAME GND\g
J 0
(-8465 2260);
DISPLAY 0.659574 (-8465 2260);
PAINT MONO (-8465 2260);
DISPLAY INVISIBLE (-8465 2260);
FORCEPROP 2 LAST CDS_LIB pure_quanta_power
J 0
(-8475 2200);
DISPLAY INVISIBLE (-8475 2200);
FORCEPROP 1 LAST HDL_POWER GND
J 1
(-8450 2125);
DISPLAY 0.872340 (-8450 2125);
PAINT GREEN (-8450 2125);
DISPLAY INVISIBLE (-8450 2125);
FORCEPROP 1 LAST PATH I9
J 0
(-8400 2200);
DISPLAY 0.872340 (-8400 2200);
PAINT AQUA (-8400 2200);
DISPLAY INVISIBLE (-8400 2200);
FORCEADD Q_RES..1
R 1
(-8875 6000);
FORCEPROP 1 LAST LOCATION PR341
J 0
(-8825 6150);
DISPLAY 0.489362 (-8825 6150);
PAINT SKYBLUE (-8825 6150);
FORCEPROP 0 LAST $SEC 1
R 1
J 0
(-8825 6175);
DISPLAY 0.680851 (-8825 6175);
PAINT MONO (-8825 6175);
DISPLAY INVISIBLE (-8825 6175);
FORCEPROP 0 LAST CDS_SEC 1
R 1
J 0
(-8825 6175);
DISPLAY 1.021277 (-8825 6175);
DISPLAY INVISIBLE (-8825 6175);
FORCEPROP 1 LASTPIN (-8875 5900) $PN 1
R 1
J 0
(-8887 5912);
DISPLAY 0.787234 (-8887 5912);
PAINT MONO (-8887 5912);
DISPLAY INVISIBLE (-8887 5912);
FORCEPROP 1 LASTPIN (-8875 6100) $PN 2
R 1
J 0
(-8887 6062);
DISPLAY 0.787234 (-8887 6062);
PAINT MONO (-8887 6062);
DISPLAY INVISIBLE (-8887 6062);
FORCEPROP 1 LAST TOLERANCE 5%
J 0
(-8825 6050);
DISPLAY 0.489362 (-8825 6050);
PAINT SKYBLUE (-8825 6050);
FORCEPROP 1 LAST PACK_TYPE 0402LF
J 0
(-8825 5850);
DISPLAY 0.489362 (-8825 5850);
PAINT SKYBLUE (-8825 5850);
FORCEPROP 1 LAST MATERIAL EMPTY
J 0
(-8825 5950);
DISPLAY 0.489362 (-8825 5950);
PAINT RED (-8825 5950);
FORCEPROP 1 LAST WATTAGE 1/16W
J 0
(-8825 6000);
DISPLAY 0.489362 (-8825 6000);
PAINT SKYBLUE (-8825 6000);
FORCEPROP 1 LAST VALUE 0
J 2
(-8800 6100);
DISPLAY 0.489362 (-8800 6100);
PAINT SKYBLUE (-8800 6100);
FORCEPROP 2 LAST CDS_LIB pure_quanta
J 0
(-8875 6000);
DISPLAY INVISIBLE (-8875 6000);
FORCEPROP 1 LAST PATH I90
R 1
J 0
(-9025 5950);
DISPLAY 0.978723 (-9025 5950);
PAINT WHITE (-9025 5950);
DISPLAY INVISIBLE (-9025 5950);
FORCEPROP 1 LAST PART_NUMBER CS00002JB13
J 0
(-8825 5900);
DISPLAY 0.489362 (-8825 5900);
PAINT SKYBLUE (-8825 5900);
DISPLAY INVISIBLE (-8825 5900);
FORCEADD ISL99390FRZTR5935..1
(-6800 4600);
FORCEPROP 1 LAST LOCATION PU35
J 0
(-7100 5475);
DISPLAY 0.489362 (-7100 5475);
PAINT SKYBLUE (-7100 5475);
FORCEPROP 2 LAST $SEC 1
J 0
(-7100 5650);
DISPLAY 0.680851 (-7100 5650);
PAINT MONO (-7100 5650);
DISPLAY INVISIBLE (-7100 5650);
FORCEPROP 2 LAST CDS_SEC 1
J 0
(-7100 5650);
DISPLAY 1.021277 (-7100 5650);
DISPLAY INVISIBLE (-7100 5650);
FORCEPROP 2 LASTPIN (-6400 4150) $PN 2
J 0
(-6390 4160);
DISPLAY 0.489362 (-6390 4160);
PAINT MONO (-6390 4160);
FORCEPROP 2 LASTPIN (-6400 4950) $PN 33
J 0
(-6390 4960);
DISPLAY 0.489362 (-6390 4960);
PAINT MONO (-6390 4960);
FORCEPROP 2 LASTPIN (-7250 4350) $PN 31
J 2
(-7260 4360);
DISPLAY 0.489362 (-7260 4360);
PAINT MONO (-7260 4360);
FORCEPROP 2 LASTPIN (-7250 4750) $PN 35
J 2
(-7260 4760);
DISPLAY 0.489362 (-7260 4760);
PAINT MONO (-7260 4760);
FORCEPROP 2 LASTPIN (-6400 4300) $PN 6
J 0
(-6390 4310);
DISPLAY 0.489362 (-6390 4310);
PAINT MONO (-6390 4310);
FORCEPROP 2 LASTPIN (-6400 4250) $PN 41
J 0
(-6390 4260);
DISPLAY 0.489362 (-6390 4260);
PAINT MONO (-6390 4260);
FORCEPROP 2 LASTPIN (-7250 4600) $PN 38
J 2
(-7260 4610);
DISPLAY 0.489362 (-7260 4610);
PAINT MONO (-7260 4610);
FORCEPROP 2 LASTPIN (-7250 4300) $PN 37
J 2
(-7260 4310);
DISPLAY 0.489362 (-7260 4310);
PAINT MONO (-7260 4310);
FORCEPROP 2 LASTPIN (-6400 4100) $PN 5
J 0
(-6390 4110);
DISPLAY 0.489362 (-6390 4110);
PAINT MONO (-6390 4110);
FORCEPROP 2 LASTPIN (-6400 4050) $PN 7_9-20_24
J 0
(-6390 4060);
DISPLAY 0.489362 (-6390 4060);
PAINT MONO (-6390 4060);
FORCEPROP 2 LASTPIN (-6400 4000) $PN 40
J 0
(-6390 4010);
DISPLAY 0.489362 (-6390 4010);
PAINT MONO (-6390 4010);
FORCEPROP 2 LASTPIN (-6400 4700) $PN 32
J 0
(-6390 4710);
DISPLAY 0.489362 (-6390 4710);
PAINT MONO (-6390 4710);
FORCEPROP 2 LASTPIN (-7250 5250) $PN 4
J 2
(-7260 5260);
DISPLAY 0.489362 (-7260 5260);
PAINT MONO (-7260 5260);
FORCEPROP 2 LASTPIN (-7250 4000) $PN 34
J 2
(-7260 4010);
DISPLAY 0.489362 (-7260 4010);
PAINT MONO (-7260 4010);
FORCEPROP 2 LASTPIN (-7250 4500) $PN 39
J 2
(-7260 4510);
DISPLAY 0.489362 (-7260 4510);
PAINT MONO (-7260 4510);
FORCEPROP 2 LASTPIN (-6400 4600) $PN 10_19
J 0
(-6390 4610);
DISPLAY 0.489362 (-6390 4610);
PAINT MONO (-6390 4610);
FORCEPROP 2 LASTPIN (-7250 4100) $PN 36
J 2
(-7260 4110);
DISPLAY 0.489362 (-7260 4110);
PAINT MONO (-7260 4110);
FORCEPROP 2 LASTPIN (-7250 4950) $PN 3
J 2
(-7260 4960);
DISPLAY 0.489362 (-7260 4960);
PAINT MONO (-7260 4960);
FORCEPROP 2 LASTPIN (-6400 5250) $PN 25_29
J 0
(-6390 5260);
DISPLAY 0.489362 (-6390 5260);
PAINT MONO (-6390 5260);
FORCEPROP 2 LASTPIN (-6400 5200) $PN 30
J 0
(-6390 5210);
DISPLAY 0.489362 (-6390 5210);
PAINT MONO (-6390 5210);
FORCEPROP 2 LASTPIN (-6400 4350) $PN 1
J 0
(-6390 4360);
DISPLAY 0.489362 (-6390 4360);
PAINT MONO (-6390 4360);
FORCEPROP 1 LAST MATERIAL IC
J 0
(-7100 5325);
DISPLAY 0.489362 (-7100 5325);
PAINT SKYBLUE (-7100 5325);
FORCEPROP 2 LAST VALUE ISL99390FRZ-TR5935
J 0
(-7100 5550);
DISPLAY 0.489362 (-7100 5550);
PAINT SKYBLUE (-7100 5550);
FORCEPROP 2 LAST PART_TYPE SMLF
J 0
(-7100 5600);
DISPLAY 0.808511 (-7100 5600);
FORCEPROP 1 LAST NEEDS_NO_SIZE TRUE
J 0
(-6800 4600);
DISPLAY 0.723404 (-6800 4600);
PAINT GREEN (-6800 4600);
DISPLAY INVISIBLE (-6800 4600);
FORCEPROP 1 LAST CDS_LMAN_SYM_OUTLINE -300,700,250,-650
J 0
(-6800 4600);
DISPLAY 0.468085 (-6800 4600);
PAINT GREEN (-6800 4600);
DISPLAY INVISIBLE (-6800 4600);
FORCEPROP 2 LAST CDS_LIB pure_quanta
J 0
(-6800 4600);
DISPLAY INVISIBLE (-6800 4600);
FORCEPROP 1 LAST PATH I91
J 0
(-6800 4600);
DISPLAY 0.723404 (-6800 4600);
PAINT GREEN (-6800 4600);
DISPLAY INVISIBLE (-6800 4600);
FORCEPROP 1 LAST PART_NUMBER AL099390004
J 0
(-7100 5400);
DISPLAY 0.489362 (-7100 5400);
PAINT SKYBLUE (-7100 5400);
DISPLAY INVISIBLE (-7100 5400);
FORCEADD Q_CAPP..1
(-3725 5500);
FORCEPROP 1 LAST LOCATION PC393
J 0
(-3675 5600);
DISPLAY 0.510638 (-3675 5600);
FORCEPROP 0 LAST $SEC 1
J 0
(-3675 5625);
DISPLAY 0.680851 (-3675 5625);
PAINT MONO (-3675 5625);
DISPLAY INVISIBLE (-3675 5625);
FORCEPROP 0 LAST CDS_SEC 1
J 0
(-3675 5625);
DISPLAY 0.680851 (-3675 5625);
DISPLAY INVISIBLE (-3675 5625);
FORCEPROP 1 LASTPIN (-3725 5600) $PN 1
J 0
(-3715 5585);
DISPLAY 0.787234 (-3715 5585);
PAINT MONO (-3715 5585);
FORCEPROP 1 LASTPIN (-3725 5400) $PN 2
J 0
(-3715 5385);
DISPLAY 0.787234 (-3715 5385);
PAINT MONO (-3715 5385);
FORCEPROP 1 LAST VALUE 270UF
J 0
(-3675 5550);
DISPLAY 0.510638 (-3675 5550);
FORCEPROP 1 LAST TOLERANCE 20%
J 0
(-3675 5500);
DISPLAY 0.510638 (-3675 5500);
FORCEPROP 1 LAST VOLTAGE 16V
J 0
(-3675 5450);
DISPLAY 0.510638 (-3675 5450);
FORCEPROP 1 LAST PACK_TYPE SMLF
J 0
(-3675 5350);
DISPLAY 0.510638 (-3675 5350);
FORCEPROP 1 LAST MATERIAL OSCON
J 0
(-3675 5400);
DISPLAY 0.510638 (-3675 5400);
FORCEPROP 2 LAST CDS_LIB pure_quanta
J 0
(-3725 5500);
DISPLAY INVISIBLE (-3725 5500);
FORCEPROP 1 LAST PATH I92
J 0
(-3675 5650);
DISPLAY 0.978723 (-3675 5650);
DISPLAY INVISIBLE (-3675 5650);
FORCEPROP 1 LAST PART_NUMBER CC72703MZ11
J 0
(-3675 5300);
DISPLAY 0.510638 (-3675 5300);
DISPLAY INVISIBLE (-3675 5300);
FORCEADD Q_CAPP..1
(-4125 5500);
FORCEPROP 1 LAST LOCATION PC390
J 0
(-4075 5600);
DISPLAY 0.510638 (-4075 5600);
FORCEPROP 0 LAST $SEC 1
J 0
(-4075 5625);
DISPLAY 0.680851 (-4075 5625);
PAINT MONO (-4075 5625);
DISPLAY INVISIBLE (-4075 5625);
FORCEPROP 0 LAST CDS_SEC 1
J 0
(-4075 5625);
DISPLAY 0.680851 (-4075 5625);
DISPLAY INVISIBLE (-4075 5625);
FORCEPROP 1 LASTPIN (-4125 5600) $PN 1
J 0
(-4115 5585);
DISPLAY 0.787234 (-4115 5585);
PAINT MONO (-4115 5585);
FORCEPROP 1 LASTPIN (-4125 5400) $PN 2
J 0
(-4115 5385);
DISPLAY 0.787234 (-4115 5385);
PAINT MONO (-4115 5385);
FORCEPROP 1 LAST VOLTAGE 16V
J 0
(-4075 5450);
DISPLAY 0.510638 (-4075 5450);
FORCEPROP 1 LAST PACK_TYPE SMLF
J 0
(-4075 5350);
DISPLAY 0.510638 (-4075 5350);
FORCEPROP 1 LAST MATERIAL OSCON
J 0
(-4075 5400);
DISPLAY 0.510638 (-4075 5400);
FORCEPROP 1 LAST TOLERANCE 20%
J 0
(-4075 5500);
DISPLAY 0.510638 (-4075 5500);
FORCEPROP 1 LAST VALUE 270UF
J 0
(-4075 5550);
DISPLAY 0.510638 (-4075 5550);
FORCEPROP 2 LAST CDS_LIB pure_quanta
J 0
(-4125 5500);
DISPLAY INVISIBLE (-4125 5500);
FORCEPROP 1 LAST PATH I93
J 0
(-4075 5650);
DISPLAY 0.978723 (-4075 5650);
DISPLAY INVISIBLE (-4075 5650);
FORCEPROP 1 LAST PART_NUMBER CC72703MZ11
J 0
(-4075 5300);
DISPLAY 0.510638 (-4075 5300);
DISPLAY INVISIBLE (-4075 5300);
FORCEADD DNS..1
(-5350 3875);
PAINT RED (-5350 3875);
FORCEPROP 2 LAST CDS_LIB mstr_misc
J 0
(-5350 3875);
DISPLAY INVISIBLE (-5350 3875);
FORCEPROP 1 LAST COMMENT_BODY TRUE
R 1
J 0
(-5275 3650);
DISPLAY 0.872340 (-5275 3650);
PAINT GREEN (-5275 3650);
DISPLAY INVISIBLE (-5275 3650);
FORCEADD DNS..1
(-5400 1800);
PAINT RED (-5400 1800);
FORCEPROP 2 LAST CDS_LIB mstr_misc
J 0
(-5400 1800);
DISPLAY INVISIBLE (-5400 1800);
FORCEPROP 1 LAST COMMENT_BODY TRUE
R 1
J 0
(-5325 1575);
DISPLAY 0.872340 (-5325 1575);
PAINT GREEN (-5325 1575);
DISPLAY INVISIBLE (-5325 1575);
FORCEADD DNS..1
(-5400 1250);
PAINT RED (-5400 1250);
FORCEPROP 2 LAST CDS_LIB mstr_misc
J 0
(-5400 1250);
DISPLAY INVISIBLE (-5400 1250);
FORCEPROP 1 LAST COMMENT_BODY TRUE
R 1
J 0
(-5325 1025);
DISPLAY 0.872340 (-5325 1025);
PAINT GREEN (-5325 1025);
DISPLAY INVISIBLE (-5325 1025);
FORCEADD DNS..1
(-8725 4075);
PAINT RED (-8725 4075);
FORCEPROP 2 LAST CDS_LIB mstr_misc
J 0
(-8725 4075);
PAINT MONO (-8725 4075);
DISPLAY INVISIBLE (-8725 4075);
FORCEPROP 1 LAST COMMENT_BODY TRUE
R 1
J 0
(-8650 3850);
DISPLAY 0.872340 (-8650 3850);
PAINT GREEN (-8650 3850);
DISPLAY INVISIBLE (-8650 3850);
FORCEADD DNS..1
(-5350 4400);
PAINT RED (-5350 4400);
FORCEPROP 2 LAST CDS_LIB mstr_misc
J 0
(-5350 4400);
DISPLAY INVISIBLE (-5350 4400);
FORCEPROP 1 LAST COMMENT_BODY TRUE
R 1
J 0
(-5275 4175);
DISPLAY 0.872340 (-5275 4175);
PAINT GREEN (-5275 4175);
DISPLAY INVISIBLE (-5275 4175);
FORCEADD DNS..1
(-8850 6000);
PAINT RED (-8850 6000);
FORCEPROP 2 LAST CDS_LIB mstr_misc
J 0
(-8850 6000);
DISPLAY INVISIBLE (-8850 6000);
FORCEPROP 1 LAST COMMENT_BODY TRUE
R 1
J 0
(-8775 5775);
DISPLAY 0.872340 (-8775 5775);
PAINT GREEN (-8775 5775);
DISPLAY INVISIBLE (-8775 5775);
FORCEADD DNS..1
(-8750 1450);
PAINT RED (-8750 1450);
FORCEPROP 2 LAST CDS_LIB mstr_misc
J 0
(-8750 1450);
PAINT MONO (-8750 1450);
DISPLAY INVISIBLE (-8750 1450);
FORCEPROP 1 LAST COMMENT_BODY TRUE
R 1
J 0
(-8675 1225);
DISPLAY 0.872340 (-8675 1225);
PAINT GREEN (-8675 1225);
DISPLAY INVISIBLE (-8675 1225);
FORCEADD QUANTA_TITLE_BLOCK_C..1
(-550 -250);
FORCEPROP 0 LAST CDS_CON_LAST_MODIFIED Thu Sep 14 16:12:21 2023
J 0
(-2435 -235);
DISPLAY INVISIBLE (-2435 -235);
FORCEPROP 1 LAST CUSTOM_TXT_CDS <CON_LAST_MODIFIED>
J 0
(-2435 -235);
DISPLAY 0.978723 (-2435 -235);
FORCEPROP 2 LAST CUSTOM_TXT_CDS <XR_PAGE_TITLE>
J 0
(-8440 5000);
DISPLAY 0.638298 (-8440 5000);
PAINT PINK (-8440 5000);
DISPLAY INVISIBLE (-8440 5000);
FORCEPROP 1 LAST CUSTOM_TXT_CDS <NAME_2>
J 0
(-3725 -200);
FORCEPROP 1 LAST CUSTOM_TXT_CDS <NAME_1>
J 0
(-3725 -75);
FORCEPROP 1 LAST CUSTOM_TXT_CDS <Q_NUMBER>
J 0
(-1953 -147);
DISPLAY 1.212766 (-1953 -147);
FORCEPROP 1 LAST CUSTOM_TXT_CDS <Q_PROJ>
J 0
(-2932 -148);
DISPLAY 1.212766 (-2932 -148);
FORCEPROP 1 LAST CUSTOM_TXT_CDS <Q_REV>
J 0
(-734 -147);
DISPLAY 1.212766 (-734 -147);
FORCEPROP 1 LAST CUSTOM_TXT_CDS <CON_PAGE_NUM> OF <CON_TOTAL_PAGES>
J 0
(-996 -232);
DISPLAY 0.978723 (-996 -232);
FORCEPROP 1 LAST Q_TITLE PVDDCR_CPU1_P1 VR PHASE 1&2
J 0
(-9825 -200);
DISPLAY 2.446809 (-9825 -200);
PAINT GREEN (-9825 -200);
FORCEPROP 2 LAST PAGE_BORDER TRUE
J 0
(-8440 5000);
DISPLAY 0.638298 (-8440 5000);
PAINT PINK (-8440 5000);
DISPLAY INVISIBLE (-8440 5000);
FORCEPROP 2 LAST CDS_LIB pure_quanta
J 0
(-550 -250);
DISPLAY INVISIBLE (-550 -250);
FORCEPROP 1 LAST CDS_LMAN_SYM_OUTLINE -9475,6775,100,-125
J 0
(-550 -250);
DISPLAY 0.468085 (-550 -250);
PAINT GREEN (-550 -250);
DISPLAY INVISIBLE (-550 -250);
FORCEPROP 2 LAST CDS_XR_PAGE_TITLE CR-218 : @T6G_MB_LIB.T6G(SCH_1):PAGE218
J 0
(-8440 5000);
DISPLAY 0.638298 (-8440 5000);
PAINT PINK (-8440 5000);
DISPLAY INVISIBLE (-8440 5000);
FORCEPROP 1 LAST Q_DEPT BU9
J 1
(-4313 -201);
DISPLAY 1.957447 (-4313 -201);
PAINT GREEN (-4313 -201);
DISPLAY INVISIBLE (-4313 -201);
FORCEPROP 1 LAST COMMENT_BODY TRUE
J 0
(-538 -263);
DISPLAY 0.978723 (-538 -263);
PAINT GREEN (-538 -263);
DISPLAY INVISIBLE (-538 -263);
WIRE 16 -1 (-9250 1450)(-9250 1500);
WIRE 16 -1 (-9225 4075)(-9225 4125);
WIRE 16 -1 (-8125 2875)(-8125 2750);
WIRE 16 -1 (-8725 4000)(-8725 3925);
WIRE 16 -1 (-9225 6150)(-9225 6100);
WIRE 16 -1 (-8575 4950)(-8575 4900);
WIRE 16 -1 (-8875 6150)(-8875 6100);
WIRE 16 -1 (-8225 5525)(-8225 5400);
WIRE 16 -1 (-8750 1375)(-8750 1300);
WIRE 16 -1 (-5375 1150)(-5375 1075);
WIRE 16 -1 (-5325 3775)(-5325 3700);
WIRE 16 -1 (-2875 5450)(-2875 5225);
WIRE 16 -1 (-2875 5750)(-2875 5825);
WIRE 16 -1 (-2875 5750)(-2875 5650);
WIRE 16 -1 (-3250 5750)(-2875 5750);
WIRE 16 -1 (-8475 2300)(-8475 2250);
WIRE 16 -1 (-8750 1675)(-7275 1675);
FORCEPROP 2 LAST SIG_NAME PVDDCR_CPU1_P1_LSET2
J 0
(-8110 1685);
DISPLAY 0.489362 (-8110 1685);
FORCEPROP 2 LASTPROP $XRERR UNIQUE?
J 0
(-8350 1685);
DISPLAY 0.638298 (-8350 1685);
PAINT MONO (-8350 1685);
DISPLAY INVISIBLE (-8350 1685);
WIRE 16 -1 (-8750 1675)(-8750 1575);
WIRE 16 -1 (-5750 750)(-4600 750);
WIRE 16 -1 (-5750 1725)(-5750 750);
WIRE 16 -1 (-6425 1725)(-5750 1725);
FORCEPROP 2 LAST SIG_NAME PVDDCR_CPU1_P1_VOS2
J 0
(-6360 1750);
DISPLAY 0.489362 (-6360 1750);
FORCEPROP 2 LASTPROP $XRERR UNIQUE?
J 0
(-6600 1750);
DISPLAY 0.638298 (-6600 1750);
PAINT MONO (-6600 1750);
DISPLAY INVISIBLE (-6600 1750);
WIRE 16 -1 (-6425 1975)(-5375 1975);
FORCEPROP 2 LAST SIG_NAME SW_PVDDCR_CPU1_P1_SW2
J 0
(-6235 1985);
DISPLAY 0.489362 (-6235 1985);
FORCEPROP 2 LASTPROP $XRERR UNIQUE?
J 0
(-6475 1985);
DISPLAY 0.638298 (-6475 1985);
PAINT MONO (-6475 1985);
DISPLAY INVISIBLE (-6475 1985);
WIRE 16 -1 (-5375 1975)(-3450 1975);
WIRE 16 -1 (-5375 1975)(-5375 1900);
WIRE 16 -1 (-4350 2075)(-4350 2100);
WIRE 16 -1 (-6425 2075)(-4350 2075);
FORCEPROP 2 LAST SIG_NAME SW_PVDDCR_CPU1_P1_BOOTR2
J 0
(-6235 2085);
DISPLAY 0.489362 (-6235 2085);
FORCEPROP 2 LASTPROP $XRERR UNIQUE?
J 0
(-6475 2085);
DISPLAY 0.638298 (-6475 2085);
PAINT MONO (-6475 2085);
DISPLAY INVISIBLE (-6475 2085);
WIRE 17 273 (-1100 2425)(-1100 3450);
WIRE 17 273 (-3000 2425)(-1100 2425);
WIRE 17 273 (-1100 3450)(-3000 3450);
WIRE 17 273 (-3000 3450)(-3000 2425);
WIRE 16 -1 (-900 4700)(-900 4600);
WIRE 16 -1 (-900 4600)(-900 4500);
WIRE 16 -1 (-900 4600)(-1250 4600);
WIRE 16 -1 (-1250 4500)(-1250 4600);
WIRE 16 -1 (-1250 4600)(-1675 4600);
WIRE 16 -1 (-1675 4600)(-1675 4500);
WIRE 16 -1 (-2025 4600)(-1675 4600);
WIRE 16 -1 (-2025 4500)(-2025 4600);
WIRE 16 -1 (-2025 4600)(-2175 4600);
WIRE 16 -1 (-2175 4600)(-3050 4600);
WIRE 16 -1 (-2175 4600)(-2175 3575);
WIRE 16 -1 (-2175 3575)(-3675 3575);
WIRE 16 -1 (-6400 5200)(-6225 5200);
WIRE 16 -1 (-6225 5200)(-6225 5250);
WIRE 16 -1 (-6225 5750)(-6225 5250);
WIRE 16 -1 (-6400 5250)(-6225 5250);
WIRE 16 -1 (-6225 5750)(-6025 5750);
WIRE 16 -1 (-6025 5750)(-5625 5750);
WIRE 16 -1 (-6025 5600)(-6025 5750);
WIRE 16 -1 (-5225 5750)(-5625 5750);
WIRE 16 -1 (-5625 5600)(-5625 5750);
WIRE 16 -1 (-4825 5750)(-5225 5750);
WIRE 16 -1 (-5225 5750)(-5225 5600);
WIRE 16 -1 (-4825 5750)(-4625 5750);
WIRE 16 -1 (-4825 5600)(-4825 5750);
WIRE 16 -1 (-4625 5750)(-4450 5750);
WIRE 16 -1 (-4625 5850)(-4625 5750);
WIRE 16 -1 (-4450 5750)(-4125 5750);
WIRE 16 -1 (-4450 5600)(-4450 5750);
WIRE 16 -1 (-4125 5750)(-3725 5750);
WIRE 16 -1 (-4125 5750)(-4125 5600);
WIRE 16 -1 (-3725 5750)(-3450 5750);
WIRE 16 -1 (-3725 5600)(-3725 5750);
WIRE 16 -1 (-6025 5400)(-6025 5250);
WIRE 16 -1 (-6025 5250)(-5625 5250);
WIRE 16 -1 (-5225 5250)(-5625 5250);
WIRE 16 -1 (-5625 5400)(-5625 5250);
WIRE 16 -1 (-4825 5250)(-5225 5250);
WIRE 16 -1 (-5225 5400)(-5225 5250);
WIRE 16 -1 (-4575 5250)(-4825 5250);
WIRE 16 -1 (-4825 5400)(-4825 5250);
WIRE 16 -1 (-4575 5250)(-4450 5250);
WIRE 16 -1 (-4575 5150)(-4575 5250);
WIRE 16 -1 (-4450 5250)(-4125 5250);
WIRE 16 -1 (-4450 5400)(-4450 5250);
WIRE 16 -1 (-4125 5250)(-3725 5250);
WIRE 16 -1 (-4125 5400)(-4125 5250);
WIRE 16 -1 (-3725 5400)(-3725 5250);
WIRE 16 -1 (-7275 2625)(-7800 2625);
WIRE 16 -1 (-7800 2625)(-7800 3175);
WIRE 16 -1 (-7800 3175)(-8125 3175);
WIRE 16 -1 (-8125 3075)(-8125 3175);
WIRE 16 -1 (-8125 3175)(-8475 3175);
WIRE 16 -1 (-8475 3300)(-8475 3175);
WIRE 16 -1 (-8475 3050)(-8475 3175);
WIRE 16 -1 (-7250 5250)(-7325 5250);
WIRE 16 -1 (-7325 5250)(-7325 5825);
WIRE 16 -1 (-7325 5825)(-8225 5825);
WIRE 16 -1 (-8225 5725)(-8225 5825);
WIRE 16 -1 (-8375 5825)(-8225 5825);
WIRE 16 -1 (-8375 6150)(-8375 5825);
WIRE 16 -1 (-8375 5825)(-8575 5825);
WIRE 16 -1 (-8575 5700)(-8575 5825);
WIRE 16 -1 (-8875 5825)(-8575 5825);
WIRE 16 -1 (-8875 5900)(-8875 5825);
WIRE 16 -1 (-9225 5825)(-8875 5825);
WIRE 16 -1 (-9225 5900)(-9225 5825);
WIRE 16 -1 (-6425 1525)(-6175 1525);
WIRE 16 -1 (-6175 1525)(-6175 1475);
WIRE 16 -1 (-6175 1475)(-6175 1425);
WIRE 16 -1 (-6425 1475)(-6175 1475);
WIRE 16 -1 (-6175 1425)(-6175 1375);
WIRE 16 -1 (-6425 1425)(-6175 1425);
WIRE 16 -1 (-6425 1375)(-6175 1375);
WIRE 16 -1 (-6175 1375)(-6175 1300);
WIRE 16 -1 (-6400 4050)(-6150 4050);
WIRE 16 -1 (-6150 4100)(-6150 4050);
WIRE 16 -1 (-6150 4050)(-6150 4000);
WIRE 16 -1 (-6400 4000)(-6150 4000);
WIRE 16 -1 (-6150 4000)(-6150 3925);
WIRE 16 -1 (-6150 4150)(-6150 4100);
WIRE 16 -1 (-6400 4100)(-6150 4100);
WIRE 16 -1 (-6400 4150)(-6150 4150);
WIRE 16 -1 (-6000 2775)(-6000 2625);
WIRE 16 -1 (-6000 2625)(-5600 2625);
WIRE 16 -1 (-5200 2625)(-5600 2625);
WIRE 16 -1 (-5600 2775)(-5600 2625);
WIRE 16 -1 (-5200 2625)(-4800 2625);
WIRE 16 -1 (-5200 2775)(-5200 2625);
WIRE 16 -1 (-4800 2625)(-4425 2625);
WIRE 16 -1 (-4800 2775)(-4800 2625);
WIRE 16 -1 (-4425 2775)(-4425 2625);
WIRE 16 -1 (-4425 2550)(-4425 2625);
WIRE 16 -1 (-6425 2575)(-6250 2575);
WIRE 16 -1 (-6250 2575)(-6250 2625);
WIRE 16 -1 (-6250 3125)(-6250 2625);
WIRE 16 -1 (-6425 2625)(-6250 2625);
WIRE 16 -1 (-6250 3125)(-6000 3125);
WIRE 16 -1 (-6000 3125)(-5600 3125);
WIRE 16 -1 (-6000 2975)(-6000 3125);
WIRE 16 -1 (-5600 3125)(-5200 3125);
WIRE 16 -1 (-5600 2975)(-5600 3125);
WIRE 16 -1 (-5200 3125)(-4800 3125);
WIRE 16 -1 (-5200 3125)(-5200 2975);
WIRE 16 -1 (-4800 3125)(-4425 3125);
WIRE 16 -1 (-4800 2975)(-4800 3125);
WIRE 16 -1 (-4425 3175)(-4425 3125);
WIRE 16 -1 (-4425 2975)(-4425 3125);
WIRE 16 -1 (-1225 1550)(-1225 1675);
WIRE 16 -1 (-1225 1500)(-1225 1550);
WIRE 16 -1 (-1225 1550)(-1650 1550);
WIRE 16 -1 (-1650 1550)(-1650 1675);
WIRE 16 -1 (-4400 750)(-1875 750);
WIRE 16 -1 (-1875 1975)(-1875 750);
WIRE 16 -1 (-1650 1975)(-1875 1975);
WIRE 16 -1 (-2650 1975)(-1875 1975);
WIRE 16 -1 (-1650 1975)(-1225 1975);
WIRE 16 -1 (-1650 1975)(-1650 1875);
WIRE 16 -1 (-1225 2025)(-1225 1975);
WIRE 16 -1 (-1225 1975)(-1225 1875);
WIRE 16 -1 (-2800 2825)(-2800 2675);
WIRE 16 -1 (-2800 2675)(-2450 2675);
WIRE 16 -1 (-2450 2675)(-2125 2675);
WIRE 16 -1 (-2450 2825)(-2450 2675);
WIRE 16 -1 (-2125 2675)(-1800 2675);
WIRE 16 -1 (-2125 2825)(-2125 2675);
WIRE 16 -1 (-1500 2675)(-1800 2675);
WIRE 16 -1 (-1800 2675)(-1800 2825);
WIRE 16 -1 (-1500 2825)(-1500 2675);
WIRE 16 -1 (-1500 2600)(-1500 2675);
WIRE 16 -1 (-2800 3025)(-2800 3125);
WIRE 16 -1 (-2800 3125)(-2450 3125);
WIRE 16 -1 (-2450 3125)(-2125 3125);
WIRE 16 -1 (-2450 3025)(-2450 3125);
WIRE 16 -1 (-2125 3125)(-1800 3125);
WIRE 16 -1 (-2125 3025)(-2125 3125);
WIRE 16 -1 (-1500 3125)(-1800 3125);
WIRE 16 -1 (-1800 3025)(-1800 3125);
WIRE 16 -1 (-1500 3175)(-1500 3125);
WIRE 16 -1 (-1500 3025)(-1500 3125);
WIRE 16 -1 (-2025 4300)(-2025 4175);
WIRE 16 -1 (-2025 4175)(-1675 4175);
WIRE 16 -1 (-1250 4175)(-1675 4175);
WIRE 16 -1 (-1675 4175)(-1675 4300);
WIRE 16 -1 (-900 4175)(-1250 4175);
WIRE 16 -1 (-1250 4300)(-1250 4175);
WIRE 16 -1 (-900 4300)(-900 4175);
WIRE 16 -1 (-900 4075)(-900 4175);
WIRE 16 -1 (-6425 2325)(-5600 2325);
FORCEPROP 2 LAST SIG_NAME SW_PVDDCR_CPU1_P1_BOOT2
J 0
(-6285 2335);
DISPLAY 0.489362 (-6285 2335);
FORCEPROP 2 LASTPROP $XRERR UNIQUE?
J 0
(-6525 2335);
DISPLAY 0.638298 (-6525 2335);
PAINT MONO (-6525 2335);
DISPLAY INVISIBLE (-6525 2335);
WIRE 16 -1 (-6400 4350)(-5725 4350);
WIRE 16 -1 (-5725 4350)(-5725 3575);
WIRE 16 -1 (-3875 3575)(-5725 3575);
FORCEPROP 2 LAST SIG_NAME PVDDCR_CPU1_P1_VOS1
J 0
(-6335 4375);
DISPLAY 0.489362 (-6335 4375);
FORCEPROP 2 LASTPROP $XRERR UNIQUE?
J 0
(-6575 4375);
DISPLAY 0.638298 (-6575 4375);
PAINT MONO (-6575 4375);
DISPLAY INVISIBLE (-6575 4375);
WIRE 16 -1 (-5325 4500)(-5325 4600);
WIRE 16 -1 (-5325 4600)(-3850 4600);
WIRE 16 -1 (-6400 4600)(-5325 4600);
FORCEPROP 2 LAST SIG_NAME SW_PVDDCR_CPU1_P1_SW1
J 0
(-6210 4610);
DISPLAY 0.489362 (-6210 4610);
FORCEPROP 2 LASTPROP $XRERR UNIQUE?
J 0
(-6450 4610);
DISPLAY 0.638298 (-6450 4610);
PAINT MONO (-6450 4610);
DISPLAY INVISIBLE (-6450 4610);
WIRE 16 -1 (-4475 4700)(-4475 4725);
WIRE 16 -1 (-6400 4700)(-4475 4700);
FORCEPROP 2 LAST SIG_NAME SW_PVDDCR_CPU1_P1_BOOTR1
J 0
(-6210 4710);
DISPLAY 0.489362 (-6210 4710);
FORCEPROP 2 LASTPROP $XRERR UNIQUE?
J 0
(-6450 4710);
DISPLAY 0.638298 (-6450 4710);
PAINT MONO (-6450 4710);
DISPLAY INVISIBLE (-6450 4710);
WIRE 16 -1 (-6400 4950)(-5650 4950);
FORCEPROP 2 LAST SIG_NAME SW_PVDDCR_CPU1_P1_BOOT1
J 0
(-6235 4960);
DISPLAY 0.489362 (-6235 4960);
FORCEPROP 2 LASTPROP $XRERR UNIQUE?
J 0
(-6475 4960);
DISPLAY 0.638298 (-6475 4960);
PAINT MONO (-6475 4960);
DISPLAY INVISIBLE (-6475 4960);
WIRE 16 -1 (-4475 4950)(-4475 4925);
WIRE 16 -1 (-5450 4950)(-4475 4950);
FORCEPROP 2 LAST SIG_NAME SW_PVDDCR_CPU1_P1_BOOT1_R
J 0
(-5235 4960);
DISPLAY 0.489362 (-5235 4960);
FORCEPROP 2 LASTPROP $XRERR UNIQUE?
J 0
(-5475 4960);
DISPLAY 0.638298 (-5475 4960);
PAINT MONO (-5475 4960);
DISPLAY INVISIBLE (-5475 4960);
WIRE 16 -1 (-4350 2325)(-4350 2300);
WIRE 16 -1 (-5400 2325)(-4350 2325);
FORCEPROP 2 LAST SIG_NAME SW_PVDDCR_CPU1_P1_BOOT2_R
J 0
(-5110 2335);
DISPLAY 0.489362 (-5110 2335);
FORCEPROP 2 LASTPROP $XRERR UNIQUE?
J 0
(-5350 2335);
DISPLAY 0.638298 (-5350 2335);
PAINT MONO (-5350 2335);
DISPLAY INVISIBLE (-5350 2335);
WIRE 16 -1 (-7375 1875)(-7375 1800);
FORCEPROP 0 LAST CDS_PHYS_NET_NAME PVDDCR_CPU1_P1_VCCS
J 0
(-7375 1825);
PAINT MONO (-7375 1825);
DISPLAY INVISIBLE (-7375 1825);
WIRE 16 -1 (-7375 1875)(-7275 1875);
WIRE 16 -1 (-8150 1875)(-7375 1875);
FORCEPROP 2 LAST SIG_NAME PVDDCR_CPU1_P1_VCCS
J 0
(-8110 1885);
DISPLAY 0.489362 (-8110 1885);
WIRE 16 -1 (-7375 1800)(-9250 1800);
WIRE 16 -1 (-9250 1800)(-9250 1700);
WIRE 16 -1 (-8725 4300)(-7250 4300);
FORCEPROP 2 LAST SIG_NAME PVDDCR_CPU1_P1_LSET1
J 0
(-8060 4310);
DISPLAY 0.489362 (-8060 4310);
FORCEPROP 2 LASTPROP $XRERR UNIQUE?
J 0
(-8300 4310);
DISPLAY 0.638298 (-8300 4310);
PAINT MONO (-8300 4310);
DISPLAY INVISIBLE (-8300 4310);
WIRE 16 -1 (-8725 4300)(-8725 4200);
WIRE 16 -1 (-7250 4600)(-8100 4600);
FORCEPROP 2 LAST SIG_NAME PVDDCR_CPU1_P1_IMON1
J 0
(-8060 4610);
DISPLAY 0.489362 (-8060 4610);
WIRE 16 -1 (-7250 4100)(-8100 4100);
FORCEPROP 2 LAST SIG_NAME PVDDCR_CPU1_P1_TEMP0
J 0
(-8060 4110);
DISPLAY 0.489362 (-8060 4110);
WIRE 16 -1 (-7250 4000)(-8100 4000);
FORCEPROP 2 LAST SIG_NAME PVDDCR_CPU1_P1_PWM1
J 0
(-8060 4010);
DISPLAY 0.489362 (-8060 4010);
WIRE 16 -1 (-7275 1475)(-8150 1475);
FORCEPROP 2 LAST SIG_NAME PVDDCR_CPU1_P1_TEMP0
J 0
(-8110 1485);
DISPLAY 0.489362 (-8110 1485);
WIRE 16 -1 (-7275 1375)(-8150 1375);
FORCEPROP 2 LAST SIG_NAME PVDDCR_CPU1_P1_PWM2
J 0
(-8110 1385);
DISPLAY 0.489362 (-8110 1385);
WIRE 16 -1 (-7275 1975)(-8150 1975);
FORCEPROP 2 LAST SIG_NAME PVDDCR_CPU1_P1_IMON2
J 0
(-8110 1985);
DISPLAY 0.489362 (-8110 1985);
WIRE 16 -1 (-7275 1725)(-7650 1725);
FORCEPROP 2 LAST SIG_NAME NC_PVDDCR_CPU1_P1_DNC2
J 0
(-7845 1735);
DISPLAY 0.489362 (-7845 1735);
FORCEPROP 2 LASTPROP $XRERR UNIQUE?
J 0
(-7890 1725);
DISPLAY 0.638298 (-7890 1725);
PAINT MONO (-7890 1725);
DISPLAY INVISIBLE (-7890 1725);
WIRE 16 -1 (-8475 2575)(-7900 2575);
WIRE 16 -1 (-8475 2850)(-8475 2575);
WIRE 16 -1 (-8475 2575)(-8475 2500);
WIRE 16 -1 (-7900 2325)(-7900 2575);
WIRE 16 -1 (-7375 2325)(-7900 2325);
FORCEPROP 2 LAST SIG_NAME PVDDCR_CPU1_P1_VCC2
J 0
(-7860 2335);
DISPLAY 0.489362 (-7860 2335);
FORCEPROP 2 LASTPROP $XRERR UNIQUE?
J 0
(-8100 2335);
DISPLAY 0.638298 (-8100 2335);
PAINT MONO (-8100 2335);
DISPLAY INVISIBLE (-8100 2335);
WIRE 16 -1 (-7275 2325)(-7375 2325);
WIRE 16 -1 (-7375 2125)(-7375 2325);
WIRE 16 -1 (-7275 2125)(-7375 2125);
WIRE 16 -1 (-5900 1625)(-6425 1625);
FORCEPROP 2 LAST SIG_NAME NC_PVDDCR_CPU1_P1_GL2_2
J 0
(-6360 1635);
DISPLAY 0.489362 (-6360 1635);
FORCEPROP 2 LASTPROP $XRERR UNIQUE?
J 0
(-5870 1625);
DISPLAY 0.638298 (-5870 1625);
PAINT MONO (-5870 1625);
DISPLAY INVISIBLE (-5870 1625);
WIRE 16 -1 (-6425 1675)(-5900 1675);
FORCEPROP 2 LAST SIG_NAME NC_PVDDCR_CPU1_P1_GL1_2
J 0
(-6360 1685);
DISPLAY 0.489362 (-6360 1685);
FORCEPROP 2 LASTPROP $XRERR UNIQUE?
J 0
(-5870 1675);
DISPLAY 0.638298 (-5870 1675);
PAINT MONO (-5870 1675);
DISPLAY INVISIBLE (-5870 1675);
WIRE 16 -1 (-5375 1700)(-5375 1350);
FORCEPROP 2 LAST SIG_NAME SW_PVDDCR_CPU1_P1_SW2_RC
J 0
(-5335 1485);
DISPLAY 0.489362 (-5335 1485);
FORCEPROP 2 LASTPROP $XRERR UNIQUE?
J 0
(-5575 1485);
DISPLAY 0.638298 (-5575 1485);
PAINT MONO (-5575 1485);
DISPLAY INVISIBLE (-5575 1485);
WIRE 16 -1 (-5325 4300)(-5325 3975);
FORCEPROP 2 LAST SIG_NAME SW_PVDDCR_CPU1_P1_SW1_RC
J 0
(-5285 4110);
DISPLAY 0.489362 (-5285 4110);
FORCEPROP 2 LASTPROP $XRERR UNIQUE?
J 0
(-5525 4110);
DISPLAY 0.638298 (-5525 4110);
PAINT MONO (-5525 4110);
DISPLAY INVISIBLE (-5525 4110);
WIRE 16 -1 (-7250 4350)(-7625 4350);
FORCEPROP 2 LAST SIG_NAME NC_PVDDCR_CPU1_P1_DNC1
J 0
(-7820 4360);
DISPLAY 0.489362 (-7820 4360);
FORCEPROP 2 LASTPROP $XRERR UNIQUE?
J 0
(-7865 4350);
DISPLAY 0.638298 (-7865 4350);
PAINT MONO (-7865 4350);
DISPLAY INVISIBLE (-7865 4350);
WIRE 16 -1 (-8575 5225)(-8000 5225);
WIRE 16 -1 (-8575 5500)(-8575 5225);
WIRE 16 -1 (-8575 5225)(-8575 5150);
WIRE 16 -1 (-8000 5225)(-8000 4950);
WIRE 16 -1 (-7350 4950)(-8000 4950);
FORCEPROP 2 LAST SIG_NAME PVDDCR_CPU1_P1_VCC1
J 0
(-7885 4960);
DISPLAY 0.489362 (-7885 4960);
FORCEPROP 2 LASTPROP $XRERR UNIQUE?
J 0
(-8125 4960);
DISPLAY 0.638298 (-8125 4960);
PAINT MONO (-8125 4960);
DISPLAY INVISIBLE (-8125 4960);
WIRE 16 -1 (-7350 4950)(-7250 4950);
WIRE 16 -1 (-7350 4750)(-7350 4950);
WIRE 16 -1 (-7250 4750)(-7350 4750);
WIRE 16 -1 (-6400 4300)(-5875 4300);
FORCEPROP 2 LAST SIG_NAME NC_PVDDCR_CPU1_P1_GL1_1
J 0
(-6335 4310);
DISPLAY 0.489362 (-6335 4310);
FORCEPROP 2 LASTPROP $XRERR UNIQUE?
J 0
(-5845 4300);
DISPLAY 0.638298 (-5845 4300);
PAINT MONO (-5845 4300);
DISPLAY INVISIBLE (-5845 4300);
WIRE 16 -1 (-6400 4250)(-5875 4250);
FORCEPROP 2 LAST SIG_NAME NC_PVDDCR_CPU1_P1_GL2_1
J 0
(-6335 4260);
DISPLAY 0.489362 (-6335 4260);
FORCEPROP 2 LASTPROP $XRERR UNIQUE?
J 0
(-5845 4250);
DISPLAY 0.638298 (-5845 4250);
PAINT MONO (-5845 4250);
DISPLAY INVISIBLE (-5845 4250);
WIRE 16 -1 (-4500 4350)(-3850 4350);
FORCEPROP 2 LAST SIG_NAME IND_CPU1_P1_CPL5
J 0
(-4360 4360);
DISPLAY 0.489362 (-4360 4360);
WIRE 16 -1 (-4050 1725)(-3450 1725);
FORCEPROP 2 LAST SIG_NAME IND_CPU1_P1_CPL1
J 0
(-3985 1735);
DISPLAY 0.489362 (-3985 1735);
WIRE 16 -1 (-2650 1725)(-2275 1725);
FORCEPROP 2 LAST SIG_NAME IND_CPU1_P1_CPL2
J 0
(-2635 1735);
DISPLAY 0.489362 (-2635 1735);
WIRE 16 -1 (-3050 4350)(-2575 4350);
FORCEPROP 2 LAST SIG_NAME IND_CPU1_P1_CPL1
J 0
(-2960 4360);
DISPLAY 0.489362 (-2960 4360);
WIRE 16 -1 (-7350 4500)(-7350 4425);
FORCEPROP 0 LAST CDS_PHYS_NET_NAME PVDDCR_CPU1_P1_VCCS
J 0
(-7350 4450);
PAINT MONO (-7350 4450);
DISPLAY INVISIBLE (-7350 4450);
WIRE 16 -1 (-7350 4500)(-7250 4500);
WIRE 16 -1 (-8100 4500)(-7350 4500);
FORCEPROP 2 LAST SIG_NAME PVDDCR_CPU1_P1_VCCS
J 0
(-8060 4510);
DISPLAY 0.489362 (-8060 4510);
WIRE 16 -1 (-7350 4425)(-9225 4425);
WIRE 16 -1 (-9225 4425)(-9225 4325);
DOT 1 (-4125 5250);
DOT 1 (-4125 5750);
DOT 1 (-3725 5750);
DOT 1 (-5600 3125);
DOT 1 (-6025 5750);
DOT 1 (-6150 4100);
DOT 1 (-5625 5250);
DOT 1 (-7350 4950);
DOT 1 (-8475 2575);
DOT 1 (-8475 3175);
DOT 1 (-8125 3175);
DOT 1 (-8575 5225);
DOT 1 (-8875 5825);
DOT 1 (-8575 5825);
DOT 1 (-8375 5825);
DOT 1 (-7375 1875);
DOT 1 (-6175 1375);
DOT 1 (-6175 1425);
DOT 1 (-6175 1475);
DOT 1 (-7375 2325);
DOT 1 (-6250 2625);
DOT 1 (-6150 4000);
DOT 1 (-6150 4050);
DOT 1 (-5375 1975);
DOT 1 (-5600 2625);
DOT 1 (-6000 3125);
DOT 1 (-5200 2625);
DOT 1 (-4800 2625);
DOT 1 (-4800 3125);
DOT 1 (-4425 2625);
DOT 1 (-4425 3125);
DOT 1 (-7350 4500);
DOT 1 (-6225 5250);
DOT 1 (-5325 4600);
DOT 1 (-5225 5250);
DOT 1 (-5625 5750);
DOT 1 (-5225 5750);
DOT 1 (-4825 5250);
DOT 1 (-4575 5250);
DOT 1 (-4450 5250);
DOT 1 (-4825 5750);
DOT 1 (-4625 5750);
DOT 1 (-4450 5750);
DOT 1 (-2450 2675);
DOT 1 (-2450 3125);
DOT 1 (-2125 2675);
DOT 1 (-2125 3125);
DOT 1 (-1875 1975);
DOT 1 (-1650 1975);
DOT 1 (-1225 1550);
DOT 1 (-1225 1975);
DOT 1 (-1800 2675);
DOT 1 (-1500 2675);
DOT 1 (-1800 3125);
DOT 1 (-1500 3125);
DOT 1 (-1675 4175);
DOT 1 (-1250 4175);
DOT 1 (-900 4175);
DOT 1 (-2175 4600);
DOT 1 (-2025 4600);
DOT 1 (-2875 5750);
DOT 1 (-1675 4600);
DOT 1 (-1250 4600);
DOT 1 (-900 4600);
DOT 1 (-8225 5825);
DOT 1 (-5200 3125);
FORCENOTE
PU35,PU5,PU37,PU36,PU38,PU33 = AL099390004/ISL99390FRZ-TR5935
(-9750 975) 0;
DISPLAY LEFT (-9750 975);
DISPLAY 1.021277 (-9750 975);
PAINT WHITE (-9750 975);
FORCENOTE
MAIN SOURCE:RENESAS BOM
(-9750 1050) 0;
DISPLAY LEFT (-9750 1050);
DISPLAY 1.276596 (-9750 1050);
PAINT WHITE (-9750 1050);
FORCENOTE
BOM NOTE
(-9750 1175) 0;
DISPLAY LEFT (-9750 1175);
DISPLAY 1.595745 (-9750 1175);
PAINT WHITE (-9750 1175);
FORCENOTE
PR272,PR266,PR267,PR259,PR258,PR428 = CS00002JB13
(-9750 675) 0;
DISPLAY LEFT (-9750 675);
DISPLAY 1.021277 (-9750 675);
PAINT WHITE (-9750 675);
FORCENOTE
PC374_1,PC373_2,PC404_3,PC403_4,PC422_5,PC136_6 = EMPTY
(-9750 450) 0;
DISPLAY LEFT (-9750 450);
DISPLAY 1.021277 (-9750 450);
PAINT WHITE (-9750 450);
FORCENOTE
3RD SOURCE:MPS BOM
(-9750 275) 0;
DISPLAY LEFT (-9750 275);
DISPLAY 1.276596 (-9750 275);
PAINT WHITE (-9750 275);
FORCENOTE
PR341,PR258,PR259,PR266,PR267,PR272,PR428 = CS00002JB13
(-9750 125) 0;
DISPLAY LEFT (-9750 125);
DISPLAY 1.021277 (-9750 125);
PAINT WHITE (-9750 125);
FORCENOTE
PU35,PU5,PU37,PU36,PU38,PU33 = AL087000A03/MP87000GMJTH-C11D-Z
(-9750 200) 0;
DISPLAY LEFT (-9750 200);
DISPLAY 1.021277 (-9750 200);
PAINT WHITE (-9750 200);
FORCENOTE
PR340,PR260,PR261,PR268,PR269,PR273,PR429 = EMPTY
(-9750 50) 0;
DISPLAY LEFT (-9750 50);
DISPLAY 1.021277 (-9750 50);
PAINT WHITE (-9750 50);
FORCENOTE
PC374_1,PC373_2,PC404_3,PC403_4,PC422_5,PC136_6 = EMPTY
(-9750 -25) 0;
DISPLAY LEFT (-9750 -25);
DISPLAY 1.021277 (-9750 -25);
PAINT WHITE (-9750 -25);
FORCENOTE
PR273,PR268,PR269,PR260,PR261,PR429 = EMPTY
(-9750 525) 0;
DISPLAY LEFT (-9750 525);
DISPLAY 1.021277 (-9750 525);
PAINT WHITE (-9750 525);
FORCENOTE
PR255,PR254,PR263,PR262,PR270,PR426 = CS00002JB13
(-9750 600) 0;
DISPLAY LEFT (-9750 600);
DISPLAY 1.021277 (-9750 600);
PAINT WHITE (-9750 600);
FORCENOTE
PU35,PU5,PU37,PU36,PU38,PU33 = AL021590000/TDA21590
(-9750 750) 0;
DISPLAY LEFT (-9750 750);
DISPLAY 1.021277 (-9750 750);
PAINT WHITE (-9750 750);
FORCENOTE
ESR=10M OHM
(-4075 5175) 0;
DISPLAY LEFT (-4075 5175);
DISPLAY 0.638298 (-4075 5175);
PAINT WHITE (-4075 5175);
FORCENOTE
IRIPPLE:5.08A
(-4075 5125) 0;
DISPLAY LEFT (-4075 5125);
DISPLAY 0.638298 (-4075 5125);
PAINT WHITE (-4075 5125);
FORCENOTE
6.3*8
(-4075 5075) 0;
DISPLAY LEFT (-4075 5075);
DISPLAY 0.638298 (-4075 5075);
PAINT WHITE (-4075 5075);
FORCENOTE
PVDDCR_CPU1_P1_PHASE2
(-7200 3150) 0;
DISPLAY LEFT (-7200 3150);
DISPLAY 1.021277 (-7200 3150);
PAINT WHITE (-7200 3150);
FORCENOTE
PVDDCR_CPU1_P1_PHASE1
(-7150 5775) 0;
DISPLAY LEFT (-7150 5775);
DISPLAY 1.021277 (-7150 5775);
PAINT WHITE (-7150 5775);
FORCENOTE
2ND SOURCE:INFENEON BOM
(-9750 825) 0;
DISPLAY LEFT (-9750 825);
DISPLAY 1.276596 (-9750 825);
PAINT WHITE (-9750 825);
FORCENOTE
2ND=CC72703MD39
(-4075 5025) 0;
DISPLAY LEFT (-4075 5025);
DISPLAY 0.638298 (-4075 5025);
PAINT WHITE (-4075 5025);
FORCENOTE
DCR=1-4,0.105M OHM
(-2650 2150) 0;
DISPLAY LEFT (-2650 2150);
DISPLAY 0.638298 (-2650 2150);
PAINT WHITE (-2650 2150);
FORCENOTE
DCR=2-3,0.27M OHM
(-2650 2100) 0;
DISPLAY LEFT (-2650 2100);
DISPLAY 0.638298 (-2650 2100);
PAINT WHITE (-2650 2100);
FORCENOTE
2ND=CV+15^0TZ01
(-2650 2050) 0;
DISPLAY LEFT (-2650 2050);
DISPLAY 0.638298 (-2650 2050);
PAINT WHITE (-2650 2050);
FORCENOTE
11.0*7.5*12.5
(-2650 2200) 0;
DISPLAY LEFT (-2650 2200);
DISPLAY 0.638298 (-2650 2200);
PAINT WHITE (-2650 2200);
FORCENOTE
PGL6303.151HLT
(-2650 2300) 0;
DISPLAY LEFT (-2650 2300);
DISPLAY 0.638298 (-2650 2300);
PAINT WHITE (-2650 2300);
FORCENOTE
ISAT:70A@100C
(-2650 2250) 0;
DISPLAY LEFT (-2650 2250);
DISPLAY 0.638298 (-2650 2250);
PAINT WHITE (-2650 2250);
FORCENOTE
7.3*4.3*1.9
(-2125 2550) 0;
DISPLAY LEFT (-2125 2550);
DISPLAY 0.638298 (-2125 2550);
PAINT WHITE (-2125 2550);
FORCENOTE
ESR=4.5M OHM
(-2125 2600) 0;
DISPLAY LEFT (-2125 2600);
DISPLAY 0.638298 (-2125 2600);
PAINT WHITE (-2125 2600);
FORCENOTE
MAIN=CH122KM8801
(-2125 2500) 0;
DISPLAY LEFT (-2125 2500);
DISPLAY 0.638298 (-2125 2500);
PAINT WHITE (-2125 2500);
FORCENOTE
ISAT:70A@100C
(-3475 5600) 0;
DISPLAY LEFT (-3475 5600);
DISPLAY 0.638298 (-3475 5600);
PAINT WHITE (-3475 5600);
FORCENOTE
PG2292.500HLT
(-3475 5650) 0;
DISPLAY LEFT (-3475 5650);
DISPLAY 0.638298 (-3475 5650);
PAINT WHITE (-3475 5650);
FORCENOTE
3RD=CVA50^0MZ08
(-3475 5400) 0;
DISPLAY LEFT (-3475 5400);
DISPLAY 0.638298 (-3475 5400);
PAINT WHITE (-3475 5400);
FORCENOTE
2ND=CVA50^0MZ07
(-3475 5450) 0;
DISPLAY LEFT (-3475 5450);
DISPLAY 0.638298 (-3475 5450);
PAINT WHITE (-3475 5450);
FORCENOTE
DCR=0.09M OHM
(-3475 5500) 0;
DISPLAY LEFT (-3475 5500);
DISPLAY 0.638298 (-3475 5500);
PAINT WHITE (-3475 5500);
FORCENOTE
6.0*6.1*7.0
(-3475 5550) 0;
DISPLAY LEFT (-3475 5550);
DISPLAY 0.638298 (-3475 5550);
PAINT WHITE (-3475 5550);
FORCENOTE
PGL6303.151HLT
(-3050 4925) 0;
DISPLAY LEFT (-3050 4925);
DISPLAY 0.638298 (-3050 4925);
PAINT WHITE (-3050 4925);
FORCENOTE
ISAT:70A@100C
(-3050 4875) 0;
DISPLAY LEFT (-3050 4875);
DISPLAY 0.638298 (-3050 4875);
PAINT WHITE (-3050 4875);
FORCENOTE
11.0*7.5*12.5
(-3050 4825) 0;
DISPLAY LEFT (-3050 4825);
DISPLAY 0.638298 (-3050 4825);
PAINT WHITE (-3050 4825);
FORCENOTE
DCR=1-4,0.105M OHM
(-3050 4775) 0;
DISPLAY LEFT (-3050 4775);
DISPLAY 0.638298 (-3050 4775);
PAINT WHITE (-3050 4775);
FORCENOTE
DCR=2-3,0.27M OHM
(-3050 4725) 0;
DISPLAY LEFT (-3050 4725);
DISPLAY 0.638298 (-3050 4725);
PAINT WHITE (-3050 4725);
FORCENOTE
2ND=CV+15^0TZ01
(-3050 4675) 0;
DISPLAY LEFT (-3050 4675);
DISPLAY 0.638298 (-3050 4675);
PAINT WHITE (-3050 4675);
QUIT
